G04 ================== begin FILE IDENTIFICATION RECORD ==================*
G04 Layout Name:  9049_F0T_FAN_BOARD_MP5048_D_v02_20221209_0830.brd*
G04 Film Name:    in1*
G04 File Format:  Gerber RS274X*
G04 File Origin:  Cadence Allegro 17.2-S081*
G04 Origin Date:  Mon Dec 12 15:05:04 2022*
G04 *
G04 Layer:  DRAWING FORMAT/TITLE_BLOCK_A*
G04 Layer:  PIN/SPECIAL_DRILL*
G04 Layer:  VIA CLASS/IN1*
G04 Layer:  PIN/IN1*
G04 Layer:  MANUFACTURING/PHOTOPLOT_OUTLINE*
G04 Layer:  ETCH/IN1*
G04 Layer:  DRAWING FORMAT/TITLE_BLOCK*
G04 Layer:  DRAWING FORMAT/TITLE_DATA_IN1*
G04 *
G04 Offset:    (0.00 0.00)*
G04 Mirror:    No*
G04 Mode:      Positive*
G04 Rotation:  0*
G04 FullContactRelief:  No*
G04 UndefLineWidth:     6.00*
G04 ================== end FILE IDENTIFICATION RECORD ====================*
%FSLAX25Y25*MOIN*%
%IR0*IPPOS*OFA0.00000B0.00000*MIA0B0*SFA1.00000B1.00000*%
%ADD11C,.02*%
%ADD12C,.054*%
%ADD10C,.085*%
%ADD13C,.014*%
%ADD14C,.018*%
%ADD15C,.006*%
%ADD16C,.009*%
%ADD19C,.03004*%
%ADD20C,.07004*%
%ADD18C,.06404*%
%ADD21C,.41004*%
%ADD17C,.16506*%
G75*
%LPD*%
G75*
G36*
G01X23583Y552000D02*
X24864D01*
G02X25006Y551941I0J-200D01*
G01X38590Y538357D01*
G02X38648Y538216I-142J-141D01*
G01Y522248D01*
G02X38559Y522082I-200J0D01*
G01X38238Y521870D01*
X38138Y521861D01*
X38091Y521881D01*
G03X37500Y522002I-591J-1381D01*
G03Y518998I0J-1502D01*
G03X38091Y519119I0J1502D01*
G01X38138Y519139D01*
X38238Y519130D01*
X38559Y518918D01*
G02X38648Y518752I-111J-166D01*
G01Y514248D01*
G02X38559Y514082I-200J0D01*
G01X38238Y513870D01*
X38138Y513861D01*
X38091Y513881D01*
G03X37500Y514002I-591J-1381D01*
G03Y510998I0J-1502D01*
G03X37767Y511022I0J1502D01*
G01X37811Y511030D01*
X37897Y511007D01*
X38167Y510782D01*
G02X38238Y510628I-129J-153D01*
G01Y470290D01*
G03X38664Y469264I1451J1D01*
G01X40388Y467539D01*
G02X40447Y467397I-141J-142D01*
G01Y459768D01*
G03X40506Y459626I200J0D01*
G01X41640Y458492D01*
G02X41698Y458351I-142J-141D01*
G01Y428334D01*
G02X41640Y428193I-200J0D01*
G01X36214Y422767D01*
X36074Y422752D01*
X36013Y422792D01*
G03X34252Y423320I-1761J-2673D01*
G03Y416916I0J-3202D01*
G03X37440Y419822I0J3202D01*
G01X37444Y419857D01*
X37473Y419920D01*
X40494Y422941D01*
G02X40636Y423000I142J-141D01*
G01X42417D01*
G02X42559Y422941I0J-200D01*
G01X42941Y422559D01*
G02X43000Y422417I-141J-142D01*
G01Y419583D01*
G03X43059Y419441I200J0D01*
G01X43740Y418760D01*
G02X43798Y418619I-142J-141D01*
G01Y416850D01*
G03X44224Y415824I1451J1D01*
G01X76490Y383557D01*
G02X76548Y383416I-142J-141D01*
G01Y352233D01*
G02X76418Y352045I-200J-1D01*
G01X76006Y351893D01*
X75885Y351925D01*
X75844Y351973D01*
G03X74700Y352502I-1144J-972D01*
G03X73198Y351000I0J-1502D01*
G03X73568Y350013I1501J0D01*
G01X73592Y349985D01*
X73617Y349918D01*
Y349582D01*
X73592Y349515D01*
X73568Y349487D01*
G03Y347513I1131J-987D01*
G01X73592Y347485D01*
X73617Y347418D01*
Y347082D01*
X73592Y347015D01*
X73568Y346987D01*
G03X73198Y346000I1131J-987D01*
G03X74700Y344498I1502J0D01*
G03X75844Y345027I0J1501D01*
G01X75885Y345075D01*
X76006Y345107D01*
X76418Y344955D01*
G02X76548Y344767I-70J-187D01*
G01Y339285D01*
G02X76490Y339144I-200J0D01*
G01X75461Y338115D01*
G02X75258Y338066I-142J141D01*
G01X74865Y338194D01*
X74792Y338279D01*
X74783Y338335D01*
G03X74432Y339087I-1483J-234D01*
G01X74408Y339115D01*
X74383Y339182D01*
Y339518D01*
X74408Y339585D01*
X74432Y339613D01*
G03X74802Y340600I-1131J987D01*
G03X71798I-1502J0D01*
G03X72168Y339613I1501J0D01*
G01X72192Y339585D01*
X72217Y339518D01*
Y339182D01*
X72192Y339115D01*
X72168Y339087D01*
G03X71798Y338100I1131J-987D01*
G03X73300Y336598I1502J0D01*
G03X73450Y336606I-5J1502D01*
G01X73496Y336610D01*
X73579Y336580D01*
X73611Y336548D01*
G02Y336265I-141J-142D01*
G01X73524Y336177D01*
G03X73098Y335151I1025J-1027D01*
G01Y303612D01*
G02X72995Y303437I-200J0D01*
G01X72641Y303241D01*
X72533Y303244D01*
X72486Y303273D01*
G03X71689Y303502I-797J-1272D01*
G03Y300498I0J-1502D01*
G03X72486Y300727I0J1501D01*
G01X72533Y300756D01*
X72641Y300759D01*
X72995Y300563D01*
G02X73098Y300388I-97J-175D01*
G01Y248641D01*
G02X73083Y248564I-200J-1D01*
G01X57020Y209784D01*
G03X56910Y209229I1341J-554D01*
G01Y157700D01*
G02X56710Y157500I-200J0D01*
G01X56700D01*
G03X56500Y157300I0J-200D01*
G01Y121704D01*
G02X56441Y121562I-200J0D01*
G01X49474Y114594D01*
G03X49048Y113568I1025J-1027D01*
G01Y73184D01*
G02X48990Y73043I-200J0D01*
G01X35685Y59738D01*
G02X35468Y59694I-142J141D01*
G03X34252Y59934I-1216J-2962D01*
G03X37454Y56732I0J-3202D01*
G03X37413Y57243I-3202J0D01*
G01X37405Y57291D01*
X37435Y57382D01*
X51526Y71474D01*
G03X51952Y72500I-1025J1027D01*
G01Y78700D01*
G02X52075Y78885I200J1D01*
G01X52132Y78908D01*
X52249Y78885D01*
X64661Y66474D01*
G03X65687Y66048I1027J1025D01*
G01X73989D01*
G02X74130Y65990I0J-200D01*
G01X76947Y63174D01*
G03X77973Y62748I1027J1025D01*
G01X84013D01*
X84037Y62743D01*
G03X84400Y62698I365J1457D01*
G03Y65702I0J1502D01*
G03X84037Y65657I2J-1502D01*
G01X84013Y65652D01*
X78657D01*
G02X78516Y65710I0J200D01*
G01X75699Y68526D01*
G03X74673Y68952I-1027J-1025D01*
G01X70288D01*
G02X70124Y69037I0J200D01*
G01X69908Y69345D01*
X69895Y69442D01*
X69912Y69488D01*
G03X70002Y70000I-1411J512D01*
G03X68500Y71502I-1502J0D01*
G03X68137Y71457I2J-1502D01*
G01X68113Y71452D01*
X66841D01*
G02X66700Y71510I0J200D01*
G01X62659Y75551D01*
G02X62600Y75693I141J142D01*
G01Y87017D01*
G02X62659Y87159I200J0D01*
G01X66441Y90941D01*
G03X66500Y91083I-141J142D01*
G01Y96865D01*
G02X66559Y97007I200J0D01*
G01X69026Y99475D01*
G03X69452Y100501I-1025J1027D01*
G01Y106400D01*
G02X69652Y106600I200J0D01*
G01X72717D01*
G03X72859Y106659I0J200D01*
G01X73941Y107741D01*
G02X74083Y107800I142J-141D01*
G01X77265D01*
G02X77449Y107677I-1J-200D01*
G01X77473Y107620D01*
X77450Y107502D01*
X75974Y106026D01*
G03X75548Y105000I1025J-1027D01*
G01Y101000D01*
G03X75974Y99974I1451J1D01*
G01X77990Y97957D01*
G02X78048Y97816I-142J-141D01*
G01Y87312D01*
X78043Y87288D01*
G03X77998Y86925I1457J-365D01*
G03X81002I1502J0D01*
G03X80957Y87288I-1502J-2D01*
G01X80952Y87312D01*
Y98500D01*
G03X80526Y99526I-1451J-1D01*
G01X78510Y101543D01*
G02X78452Y101684I142J141D01*
G01Y102637D01*
G02X78537Y102801I200J0D01*
G01X78845Y103017D01*
X78942Y103030D01*
X78988Y103013D01*
G03X79500Y102923I512J1411D01*
G03X80883Y103840I0J1501D01*
G01X80899Y103876D01*
X85626Y108604D01*
G03X86052Y109630I-1025J1027D01*
G01Y113700D01*
G02X86252Y113900I200J0D01*
G01X86717D01*
G03X86859Y113959I0J200D01*
G01X87441Y114541D01*
G03X87500Y114683I-141J142D01*
G01Y117317D01*
G03X87441Y117459I-200J0D01*
G01X86459Y118441D01*
G03X86317Y118500I-142J-141D01*
G01X86252D01*
G02X86052Y118700I0J200D01*
G01Y118969D01*
G02X86110Y119110I200J0D01*
G01X86441Y119441D01*
G03X86500Y119583I-141J142D01*
G01Y121494D01*
G02X86559Y121636I200J0D01*
G01X89126Y124204D01*
G03X89197Y124280I-1024J1028D01*
G01X89418Y124197D01*
G02X89548Y124010I-70J-187D01*
G01Y121186D01*
G02X89480Y121035I-200J-1D01*
G01X89221Y120808D01*
X89140Y120783D01*
X89096Y120789D01*
G03X88900Y120802I-197J-1489D01*
G03Y117798I0J-1502D01*
G03X89096Y117811I-1J1502D01*
G01X89140Y117817D01*
X89221Y117792D01*
X89480Y117565D01*
G02X89548Y117414I-132J-150D01*
G01Y109684D01*
G02X89490Y109543I-200J0D01*
G01X84974Y105026D01*
G03X84548Y104000I1025J-1027D01*
G01Y92387D01*
X84543Y92363D01*
G03X84498Y92000I1457J-365D01*
G03X87502I1502J0D01*
G03X87457Y92363I-1502J-2D01*
G01X87452Y92387D01*
Y103316D01*
G02X87510Y103457I200J0D01*
G01X92026Y107974D01*
G03X92452Y109000I-1025J1027D01*
G01Y133769D01*
G02X92510Y133910I200J0D01*
G01X92882Y134282D01*
G02X93165I141J-142D01*
G01X104890Y122556D01*
G02X104948Y122415I-142J-141D01*
G01Y94300D01*
G03X105374Y93274I1451J1D01*
G01X109441Y89206D01*
G02X109500Y89064I-141J-142D01*
G01Y88683D01*
G03X109559Y88541I200J0D01*
G01X112641Y85459D01*
G03X112783Y85400I142J141D01*
G01X116243D01*
G02X116385Y85341I0J-200D01*
G01X116966Y84760D01*
G02X117024Y84619I-142J-141D01*
G01Y83888D01*
X117018Y83864D01*
G03X116973Y83500I1457J-365D01*
G03X117586Y82289I1503J0D01*
G01X117622Y82263D01*
X117664Y82187D01*
X117690Y81841D01*
G02X117632Y81684I-199J-16D01*
G01X114892Y78943D01*
G03X114466Y77917I1025J-1027D01*
G01Y76037D01*
X114461Y76013D01*
G03X114416Y75650I1457J-365D01*
G03X115322Y74271I1502J0D01*
G01X115368Y74252D01*
X115429Y74174D01*
X115501Y73800D01*
G02X115446Y73621I-197J-38D01*
G01X110834Y69010D01*
G02X110693Y68952I-141J142D01*
G01X100499D01*
G03X99473Y68526I1J-1451D01*
G01X97974Y67027D01*
G03X97548Y66001I1025J-1027D01*
G01Y61387D01*
X97543Y61363D01*
G03X97498Y61000I1457J-365D01*
G03X100502I1502J0D01*
G03X100457Y61363I-1502J-2D01*
G01X100452Y61387D01*
Y65317D01*
G02X100510Y65458I200J0D01*
G01X101042Y65990D01*
G02X101183Y66048I141J-142D01*
G01X111274D01*
G02X111459Y65925I1J-200D01*
G01X111482Y65868D01*
X111459Y65751D01*
X104718Y59010D01*
G02X104577Y58952I-141J142D01*
G01X100270D01*
X100246Y58957D01*
G03X99883Y59002I-365J-1457D01*
G03Y55998I0J-1502D01*
G03X100246Y56043I-2J1502D01*
G01X100270Y56048D01*
X105261D01*
G03X106287Y56474I-1J1451D01*
G01X122640Y72827D01*
G03X123066Y73853I-1025J1027D01*
G01Y74930D01*
G02X123124Y75071I200J0D01*
G01X125006Y76953D01*
G02X125180Y77009I141J-141D01*
G01X125550Y76946D01*
X125627Y76889D01*
X125648Y76845D01*
G03X127000Y75998I1352J656D01*
G03X127363Y76043I-2J1502D01*
G01X127387Y76048D01*
X127425D01*
G03X128451Y76474I-1J1451D01*
G01X130650Y78673D01*
G03X131076Y79699I-1025J1027D01*
G01Y91710D01*
G02X131199Y91895I200J1D01*
G01X131256Y91918D01*
X131373Y91895D01*
X132871Y90398D01*
G03X133897Y89972I1027J1025D01*
G01X143924D01*
G03X144950Y90398I-1J1451D01*
G01X151026Y96474D01*
G03X151452Y97500I-1025J1027D01*
G01Y111406D01*
G02X151575Y111591I200J1D01*
G01X151632Y111614D01*
X151749Y111591D01*
X166200Y97140D01*
X166227Y97035D01*
X166212Y96982D01*
G03X166089Y96102I3079J-879D01*
G03X169291Y99304I3202J0D01*
G03X168411Y99181I-1J-3202D01*
G01X168358Y99166D01*
X168253Y99193D01*
X154010Y113436D01*
G02X153952Y113577I142J141D01*
G01Y135700D01*
G03X153526Y136726I-1451J-1D01*
G01X147751Y142502D01*
G02X147713Y142733I141J142D01*
G01X147911Y143130D01*
X148025Y143190D01*
X148089Y143181D01*
G03X148576Y143147I487J3468D01*
G03X149995Y143447I1J3502D01*
G02X150157I81J-182D01*
G03X151576Y143147I1418J3202D01*
G03X152995Y143447I1J3502D01*
G02X153157I81J-182D01*
G03X154576Y143147I1418J3202D01*
G03X158078Y146649I0J3502D01*
G03X157872Y147831I-3502J-1D01*
G02Y147967I189J68D01*
G03X158078Y149149I-3296J1183D01*
G03X154576Y152651I-3502J0D01*
G03X153157Y152351I-1J-3502D01*
G02X152995I-81J182D01*
G03X151576Y152651I-1418J-3202D01*
G03X150157Y152351I-1J-3502D01*
G02X149995I-81J182D01*
G03X148576Y152651I-1418J-3202D01*
G03X146624Y152057I-1J-3502D01*
G01X146578Y152026D01*
X146468Y152020D01*
X146107Y152212D01*
G02X146002Y152389I95J176D01*
G01Y163303D01*
G02X146144Y163494I200J0D01*
G01X146576Y163623D01*
X146699Y163578D01*
X146736Y163522D01*
G03X149664Y161941I2928J1921D01*
G03X153166Y165443I0J3502D01*
G03X152866Y166862I-3502J1D01*
G02Y167024I182J81D01*
G03X153166Y168443I-3202J1418D01*
G03X152866Y169862I-3502J1D01*
G02Y170024I182J81D01*
G03X153166Y171443I-3202J1418D01*
G03X152866Y172862I-3502J1D01*
G02Y173024I182J81D01*
G03X153166Y174443I-3202J1418D01*
G03X149664Y177945I-3502J0D01*
G03X146736Y176364I0J-3502D01*
G01X146699Y176308D01*
X146576Y176263D01*
X146144Y176392D01*
G02X146002Y176583I58J191D01*
G01Y202543D01*
G03X145891Y203098I-1452J-2D01*
G01X136566Y225613D01*
G02X136606Y225827I185J76D01*
G01X136899Y226135D01*
X137013Y226163D01*
X137069Y226143D01*
G03X138238Y225942I1169J3301D01*
G03X139458Y226161I1J3502D01*
G02X139598I70J-187D01*
G03X140818Y225942I1219J3283D01*
G03X142019Y226155I-2J3502D01*
G02X142157I69J-188D01*
G03X143358Y225942I1203J3289D01*
G03X146860Y229444I0J3502D01*
G03X146654Y230626I-3502J-1D01*
G02Y230762I189J68D01*
G03X146682Y230841I-3286J1209D01*
G01X146701Y230898D01*
X146794Y230972D01*
X147278Y231016D01*
X147383Y230960D01*
X147412Y230908D01*
G03X150482Y229091I3070J1685D01*
G03X151683Y229304I-2J3502D01*
G02X151821I69J-188D01*
G03X153022Y229091I1203J3289D01*
G03X154223Y229304I-2J3502D01*
G02X154361I69J-188D01*
G03X155562Y229091I1203J3289D01*
G03X159064Y232593I0J3502D01*
G03X158858Y233775I-3502J-1D01*
G02Y233911I189J68D01*
G03X159064Y235093I-3296J1183D01*
G03X155562Y238595I-3502J0D01*
G03X154342Y238376I-1J-3502D01*
G02X154202I-70J187D01*
G03X152982Y238595I-1219J-3283D01*
G03X151800Y238389I1J-3502D01*
G02X151664I-68J189D01*
G03X150482Y238595I-1183J-3296D01*
G03X146980Y235093I0J-3502D01*
G03X147186Y233911I3502J1D01*
G02Y233775I-189J-68D01*
G03X147158Y233696I3286J-1209D01*
G01X147139Y233639D01*
X147046Y233565D01*
X146562Y233521D01*
X146457Y233577D01*
X146428Y233629D01*
G03X143358Y235446I-3070J-1685D01*
G03X142138Y235227I-1J-3502D01*
G02X141998I-70J187D01*
G03X140778Y235446I-1219J-3283D01*
G03X139558Y235227I-1J-3502D01*
G02X139418I-70J187D01*
G03X138198Y235446I-1219J-3283D01*
G03X134696Y231944I0J-3502D01*
G03X134921Y230709I3502J0D01*
G02X134923Y230574I-187J-70D01*
G03X134909Y230532I3315J-1128D01*
G01X134896Y230491D01*
X134836Y230427D01*
X134796Y230410D01*
G02X134535Y230518I-76J185D01*
G01X126829Y249122D01*
G02X126876Y249343I185J76D01*
G01X127190Y249644D01*
X127310Y249664D01*
X127367Y249638D01*
G03X128000Y249498I633J1361D01*
G03Y252502I0J1502D01*
G03X126589Y251516I0J-1503D01*
G01X126568Y251457D01*
X126468Y251386D01*
X126033Y251377D01*
G02X125844Y251500I-4J200D01*
G01X124977Y253595D01*
G02X124962Y253671I185J76D01*
G01Y308953D01*
G02X125066Y309128I200J0D01*
G01X125424Y309323D01*
X125532Y309319D01*
X125579Y309288D01*
G03X127482Y308726I1903J2941D01*
G03X128901Y309026I1J3502D01*
G02X129063I81J-182D01*
G03X130482Y308726I1418J3202D01*
G03X131901Y309026I1J3502D01*
G02X132063I81J-182D01*
G03X133482Y308726I1418J3202D01*
G03X136984Y312228I0J3502D01*
G03X136684Y313647I-3502J1D01*
G02Y313809I182J81D01*
G03X136984Y315228I-3202J1418D01*
G03X133482Y318730I-3502J0D01*
G03X132063Y318430I-1J-3502D01*
G02X131901I-81J182D01*
G03X130482Y318730I-1418J-3202D01*
G03X129063Y318430I-1J-3502D01*
G02X128901I-81J182D01*
G03X127482Y318730I-1418J-3202D01*
G03X126704Y318642I2J-3502D01*
G01X126653Y318631D01*
X126557Y318658D01*
X126242Y318965D01*
X126212Y319061D01*
X126223Y319112D01*
G03X126252Y319400I-1423J289D01*
G01Y343665D01*
G02X126369Y343847I200J0D01*
G01X126754Y344023D01*
X126869Y344006D01*
X126914Y343967D01*
G03X127900Y343598I986J1133D01*
G03X129402Y345100I0J1502D01*
G03X128750Y346338I-1501J0D01*
G01X128708Y346367D01*
X128662Y346458D01*
X128676Y346897D01*
X128727Y346985D01*
X128771Y347011D01*
G03X129502Y348300I-771J1289D01*
G03X128000Y349802I-1502J0D01*
G03X126935Y349359I0J-1502D01*
G01X126892Y349316D01*
X126773Y349292D01*
X126375Y349456D01*
G02X126252Y349641I77J185D01*
G01Y350365D01*
G02X126369Y350547I200J0D01*
G01X126754Y350723D01*
X126869Y350706D01*
X126914Y350667D01*
G03X127900Y350298I986J1133D01*
G03Y353302I0J1502D01*
G03X126914Y352933I0J-1502D01*
G01X126869Y352894D01*
X126754Y352877D01*
X126369Y353053D01*
G02X126252Y353235I83J182D01*
G01Y362865D01*
G02X126369Y363047I200J0D01*
G01X126754Y363223D01*
X126869Y363206D01*
X126914Y363167D01*
G03X127900Y362798I986J1133D01*
G03Y365802I0J1502D01*
G03X126914Y365433I0J-1502D01*
G01X126869Y365394D01*
X126754Y365377D01*
X126369Y365553D01*
G02X126252Y365735I83J182D01*
G01Y366465D01*
G02X126369Y366647I200J0D01*
G01X126754Y366823D01*
X126869Y366806D01*
X126914Y366767D01*
G03X127900Y366398I986J1133D01*
G03X129402Y367900I0J1502D01*
G03X128783Y369115I-1502J0D01*
G01X128745Y369143D01*
X128702Y369224D01*
X128688Y369633D01*
X128726Y369716D01*
X128762Y369746D01*
G03X129302Y370900I-963J1154D01*
G03X127800Y372402I-1502J0D01*
G03X126893Y372097I0J-1501D01*
G01X126847Y372062D01*
X126735Y372052D01*
X126362Y372237D01*
G02X126252Y372416I90J179D01*
G01Y373416D01*
G02X126310Y373557I200J0D01*
G01X141743Y388990D01*
G02X141884Y389048I141J-142D01*
G01X145501D01*
G03X146527Y389474I-1J1451D01*
G01X155791Y398737D01*
G02X155932Y398796I142J-141D01*
G01X181183D01*
G03X181348Y398805I4J1451D01*
G01X181409Y398812D01*
G03X182151Y399121I-165J1442D01*
G01X182201Y399161D01*
G03X182320Y399268I-909J1131D01*
G01X188494Y405441D01*
G02X188636Y405500I142J-141D01*
G01X189417D01*
G02X189559Y405441I0J-200D01*
G01X190184Y404816D01*
G02X190242Y404675I-142J-141D01*
G01Y286878D01*
G02X190184Y286737I-200J0D01*
G01X183357Y279910D01*
G02X183216Y279852I-141J142D01*
G01X180273D01*
G03X179247Y279426I1J-1451D01*
G01X175105Y275285D01*
X175084Y275272D01*
G03X174356Y273985I774J-1287D01*
G03X175858Y272483I1502J0D01*
G03X177145Y273211I0J1502D01*
G01X177158Y273232D01*
X180816Y276890D01*
G02X180957Y276948I141J-142D01*
G01X183900D01*
G03X184926Y277374I-1J1451D01*
G01X189994Y282441D01*
G02X190136Y282500I142J-141D01*
G01X191217D01*
G02X191359Y282441I0J-200D01*
G01X191741Y282059D01*
G02X191800Y281917I-141J-142D01*
G01Y271306D01*
G02X191741Y271164I-200J0D01*
G01X188187Y267610D01*
G02X188046Y267552I-141J142D01*
G01X174084D01*
G02X173943Y267610I0J200D01*
G01X167058Y274495D01*
G02X167002Y274669I141J142D01*
G01X167063Y275037D01*
X167120Y275115D01*
X167164Y275136D01*
G03X168001Y276483I-665J1347D01*
G03X167801Y277231I-1502J-1D01*
G01X167776Y277275D01*
X167773Y277372D01*
X167959Y277760D01*
X168037Y277818D01*
X168087Y277826D01*
G03X169360Y279310I-228J1484D01*
G03X167858Y280812I-1502J0D01*
G03X167054Y280579I0J-1502D01*
G01X167009Y280550D01*
X166906Y280545D01*
X166506Y280740D01*
X166447Y280824D01*
X166442Y280877D01*
G03X164947Y282230I-1495J-149D01*
G03X163660Y281502I0J-1502D01*
G01X163647Y281481D01*
X162774Y280607D01*
G03X162348Y279581I1025J-1027D01*
G01Y277186D01*
G02X162236Y277007I-200J0D01*
G01X161861Y276824D01*
X161748Y276836D01*
X161702Y276871D01*
G03X160777Y277190I-925J-1182D01*
G03X160414Y277145I2J-1502D01*
G01X160390Y277140D01*
X159182D01*
G02X159041Y277198I0J200D01*
G01X157772Y278467D01*
G02X157714Y278619I141J141D01*
G01X157731Y278959D01*
X157770Y279033D01*
X157803Y279061D01*
G03X158360Y280228I-944J1167D01*
G03X156858Y281730I-1502J0D01*
G03X156695Y281721I1J-1502D01*
G01X156652Y281716D01*
X156572Y281742D01*
X156318Y281970D01*
G02X156252Y282119I134J148D01*
G01Y297116D01*
G02X156310Y297257I200J0D01*
G01X157815Y298763D01*
G02X158032Y298806I141J-142D01*
G01X158430Y298644D01*
X158497Y298545D01*
X158498Y298484D01*
G03X160000Y296998I1502J16D01*
G03Y300002I0J1502D01*
G03X159510Y299920I0J-1502D01*
G01X159455Y299901D01*
X159344Y299926D01*
X159303Y299967D01*
G02Y300250I141J142D01*
G01X159543Y300490D01*
G02X159684Y300548I141J-142D01*
G01X161497D01*
G02X161648Y300479I0J-200D01*
G03X162783Y299961I1135J984D01*
G03X164285Y301463I0J1502D01*
G03X163557Y302750I-1502J0D01*
G01X163536Y302763D01*
X163272Y303026D01*
G03X162246Y303452I-1027J-1025D01*
G01X159000D01*
G03X157974Y303026I1J-1451D01*
G01X153774Y298826D01*
G03X153404Y298196I1026J-1026D01*
G01X153392Y298156D01*
X153341Y298093D01*
X153013Y297919D01*
X152932Y297913D01*
X152893Y297926D01*
G03X152420Y298002I-472J-1426D01*
G03X150983Y296936I0J-1502D01*
G01X150969Y296889D01*
X150902Y296820D01*
X150503Y296684D01*
X150408Y296697D01*
X150369Y296725D01*
G03X149500Y297002I-869J-1225D01*
G03Y293998I0J-1502D01*
G03X150937Y295064I0J1502D01*
G01X150951Y295111D01*
X151018Y295180D01*
X151417Y295316D01*
X151512Y295303D01*
X151551Y295275D01*
G03X152420Y294998I869J1225D01*
G03X152837Y295057I0J1503D01*
G01X152883Y295070D01*
X152975Y295054D01*
X153269Y294833D01*
G02X153348Y294673I-121J-159D01*
G01Y279386D01*
G03X153774Y278360I1451J1D01*
G01X157472Y274662D01*
G03X157518Y274617I1038J1015D01*
G01X157564Y274575D01*
X157592Y274456D01*
X157434Y274050D01*
G02X157248Y273922I-187J72D01*
G01X136869D01*
X136845Y273928D01*
G03X136482Y273973I-365J-1457D01*
G03Y270969I0J-1502D01*
G03X136845Y271014I-2J1502D01*
G01X136869Y271020D01*
X140684D01*
G02X140853Y270926I-1J-200D01*
G01X141061Y270596D01*
X141067Y270494D01*
X141045Y270447D01*
G03X140898Y269800I1355J-648D01*
G03X140943Y269437I1502J2D01*
G01X140948Y269413D01*
Y268270D01*
G02X140840Y268092I-200J-1D01*
G01X140472Y267904D01*
X140360Y267913D01*
X140314Y267946D01*
G03X139435Y268230I-879J-1218D01*
G03Y265226I0J-1502D01*
G03X140314Y265510I0J1502D01*
G01X140360Y265543D01*
X140472Y265552D01*
X140840Y265364D01*
G02X140948Y265186I-92J-177D01*
G01Y264284D01*
G02X140890Y264143I-200J0D01*
G01X139674Y262926D01*
G03X139248Y261900I1025J-1027D01*
G01Y253300D01*
G03X139674Y252274I1451J1D01*
G01X145974Y245974D01*
G03X147000Y245548I1027J1025D01*
G01X150113D01*
X150137Y245543D01*
G03X150500Y245498I365J1457D01*
G03X152002Y247000I0J1502D01*
G03X151923Y247481I-1502J0D01*
G01X151906Y247530D01*
X151924Y247630D01*
X152198Y247973D01*
X152292Y248013D01*
X152343Y248007D01*
G03X152500Y247999I155J1494D01*
G03X150998Y249501I0J1502D01*
G03X151077Y249020I1502J0D01*
G01X151094Y248971D01*
X151076Y248871D01*
X150802Y248528D01*
X150708Y248488D01*
X150657Y248494D01*
G03X150500Y248502I-155J-1494D01*
G03X150137Y248457I2J-1502D01*
G01X150113Y248452D01*
X150038D01*
G02X149838Y248652I0J200D01*
G01Y248699D01*
X149879Y248781D01*
X149916Y248810D01*
G03X150502Y250000I-915J1190D01*
G03X147498I-1502J0D01*
G03X148084Y248810I1501J0D01*
G01X148121Y248781D01*
X148162Y248699D01*
Y248652D01*
G02X147962Y248452I-200J0D01*
G01X147684D01*
G02X147543Y248510I0J200D01*
G01X142210Y253843D01*
G02X142152Y253984I142J141D01*
G01Y261216D01*
G02X142210Y261357I200J0D01*
G01X143426Y262574D01*
G03X143852Y263600I-1025J1027D01*
G01Y263840D01*
G02X143919Y263990I200J1D01*
G01X144175Y264217D01*
X144257Y264242D01*
X144300Y264237D01*
G03X144482Y264226I181J1491D01*
G03X145631Y264761I0J1501D01*
G02X145784Y264832I153J-129D01*
G01X146091D01*
G02X146244Y264761I0J-200D01*
G03X147393Y264226I1149J966D01*
G03X148680Y264954I0J1502D01*
G01X148693Y264975D01*
X152542Y268824D01*
G02X152683Y268882I141J-142D01*
G01X159070D01*
G02X159211Y268824I0J-200D01*
G01X167962Y260074D01*
G03X168988Y259648I1027J1025D01*
G01X189800D01*
G03X190826Y260074I-1J1451D01*
G01X196294Y265541D01*
G02X196436Y265600I142J-141D01*
G01X197817D01*
G02X197959Y265541I0J-200D01*
G01X198484Y265016D01*
G02X198542Y264875I-142J-141D01*
G01Y15748D01*
G02X187795Y5000I-10747J-1D01*
G01X146800D01*
G02X146658Y5059I0J200D01*
G01X143799Y7918D01*
G02X143740Y8060I141J142D01*
G01Y43307D01*
G03X132998Y52979I-9725J0D01*
G01Y52200D01*
G02X132798Y52000I-200J0D01*
G01X118423D01*
G02X118283Y52057I0J200D01*
G01X118055Y52279D01*
X118024Y52350D01*
X118023Y52390D01*
G03X114522Y55802I-3501J-90D01*
G03X113103Y55502I-1J-3502D01*
G02X112941I-81J182D01*
G03X111522Y55802I-1418J-3202D01*
G03X108021Y52390I0J-3502D01*
G01X108020Y52350D01*
X107989Y52279D01*
X107761Y52057D01*
G02X107621Y52000I-140J143D01*
G01X70702D01*
G02X70502Y52200I0J200D01*
G01Y52832D01*
G03X70302Y53032I-201J0D01*
G01X69498D01*
X69497Y53031D01*
G03X59802Y43307I29J-9724D01*
G01Y8060D01*
G02X59744Y7918I-200J-1D01*
G01X56885Y5059D01*
G02X56743Y5000I-142J141D01*
G01X15748D01*
G02X5000Y15748I0J10748D01*
G01Y40711D01*
G02X5104Y40886I200J-1D01*
G01X5461Y41082D01*
X5569Y41078D01*
X5616Y41048D01*
G03X7500Y40498I1884J2952D01*
G03Y47502I0J3502D01*
G03X5616Y46952I0J-3502D01*
G01X5569Y46922D01*
X5461Y46918D01*
X5104Y47114D01*
G02X5000Y47289I96J176D01*
G01Y277464D01*
G02X5124Y277649I200J0D01*
G01X5181Y277672D01*
X5298Y277649D01*
X9200Y273747D01*
X9213Y273726D01*
G03X10500Y272998I1287J774D01*
G03X11776Y273708I0J1502D01*
G01X11801Y273748D01*
X11877Y273796D01*
X12235Y273837D01*
G02X12399Y273780I23J-198D01*
G01X13706Y272474D01*
G03X14732Y272048I1027J1025D01*
G01X18349D01*
G02X18490Y271990I0J-200D01*
G01X19796Y270684D01*
G03X19938Y270625I142J141D01*
G01X24131D01*
G03X24273Y270684I0J200D01*
G01X25579Y271990D01*
G02X25720Y272048I141J-142D01*
G01X26277D01*
G02X26451Y271947I0J-200D01*
G01X26650Y271598D01*
X26649Y271491D01*
X26621Y271444D01*
G03X26410Y270676I1292J-768D01*
G03X29414I1502J0D01*
G03X29168Y271499I-1502J-1D01*
G01X29142Y271539D01*
X29131Y271633D01*
X29278Y272026D01*
X29348Y272090D01*
X29394Y272103D01*
G03X30026Y272474I-395J1397D01*
G01X30898Y273346D01*
G02X31181I141J-142D01*
G01X31203Y273324D01*
X31231Y273270D01*
X31237Y273239D01*
G03X31259Y273137I1478J265D01*
G01X31264Y273113D01*
Y268203D01*
G03X31690Y267177I1451J1D01*
G01X32990Y265876D01*
G02X33048Y265735I-142J-141D01*
G01Y262788D01*
G02X32963Y262624I-200J0D01*
G01X32655Y262408D01*
X32558Y262395D01*
X32512Y262412D01*
G03X32000Y262502I-512J-1411D01*
G03Y259498I0J-1502D01*
G03X32512Y259588I0J1501D01*
G01X32558Y259605D01*
X32655Y259592D01*
X32963Y259376D01*
G02X33048Y259212I-115J-164D01*
G01Y248325D01*
G02X32990Y248184I-200J0D01*
G01X31573Y246766D01*
G02X31359Y246721I-142J142D01*
G01X30962Y246875D01*
X30893Y246970D01*
X30890Y247030D01*
G03X29390Y248462I-1500J-70D01*
G03X27888Y246960I0J-1502D01*
G03X28169Y246085I1503J0D01*
G01X28203Y246038D01*
X28211Y245928D01*
X28022Y245560D01*
G02X27844Y245452I-177J92D01*
G01X27732D01*
G02X27591Y245510I0J200D01*
G01X27480Y245621D01*
X27465Y245666D01*
G03X26040Y246692I-1425J-477D01*
G03X24538Y245190I0J-1502D01*
G03X24620Y244699I1502J-1D01*
G02X24626Y244679I-188J-67D01*
G03X25014Y243982I1413J330D01*
G01X26022Y242974D01*
G03X27048Y242548I1027J1025D01*
G01X30859D01*
G03X31885Y242974I-1J1451D01*
G01X35526Y246615D01*
G03X35952Y247641I-1025J1027D01*
G01Y247679D01*
G02X36152Y247879I200J0D01*
G01X36196D01*
X36237Y247860D01*
G03X36880Y247715I644J1357D01*
G03Y250719I0J1502D01*
G03X36463Y250660I0J-1503D01*
G01X36417Y250647D01*
X36325Y250663D01*
X36031Y250884D01*
G02X35952Y251044I121J159D01*
G01Y266419D01*
G03X35526Y267445I-1451J-1D01*
G01X34226Y268746D01*
G02X34168Y268887I142J141D01*
G01Y273113D01*
X34173Y273137D01*
G03X34208Y273324I-1456J369D01*
G01X34214Y273382D01*
X34286Y273470D01*
X34681Y273607D01*
G02X34888Y273560I66J-189D01*
G01X41006Y267441D01*
G02X41064Y267285I-141J-141D01*
G01X41040Y266940D01*
X40999Y266865D01*
X40963Y266838D01*
G03X40362Y265636I901J-1202D01*
G03X43366I1502J0D01*
G03X43278Y266142I-1502J-1D01*
G01X43262Y266189D01*
X43274Y266284D01*
X43491Y266592D01*
G02X43655Y266676I163J-116D01*
G01X47676D01*
G03X48702Y267102I-1J1451D01*
G01X53210Y271609D01*
G02X53380Y271665I141J-142D01*
G01X53745Y271612D01*
X53822Y271558D01*
X53845Y271516D01*
G03X55167Y270726I1322J711D01*
G03X56352Y271305I0J1502D01*
G02X56509Y271382I158J-123D01*
G01X56825D01*
G02X56982Y271305I-1J-200D01*
G03X59352I1185J923D01*
G02X59509Y271382I158J-123D01*
G01X59825D01*
G02X59982Y271305I-1J-200D01*
G03X62352I1185J923D01*
G02X62509Y271382I158J-123D01*
G01X62825D01*
G02X62982Y271305I-1J-200D01*
G03X64167Y270726I1185J923D01*
G03X65668Y272165I0J1502D01*
G01X65670Y272211D01*
X65712Y272291D01*
X66038Y272530D01*
X66127Y272546D01*
X66171Y272534D01*
G03X66561Y272483I388J1451D01*
G03X68063Y273985I0J1502D01*
G03X67335Y275272I-1502J0D01*
G01X67314Y275285D01*
X66572Y276026D01*
G03X65546Y276452I-1027J-1025D01*
G01X58102D01*
G02X57918Y276573I0J200D01*
G01X57750Y276967D01*
X57772Y277085D01*
X57813Y277129D01*
G03X58232Y278169I-1083J1041D01*
G03X58139Y278688I-1502J-1D01*
G01X58122Y278735D01*
X58135Y278833D01*
X58386Y279183D01*
X58475Y279228D01*
X58524Y279226D01*
X58561D01*
G03Y282230I0J1502D01*
G03X57412Y281695I0J-1501D01*
G02X57259Y281624I-153J129D01*
G01X56952D01*
G02X56799Y281695I0J200D01*
G03X55650Y282230I-1149J-966D01*
G03X54363Y281502I0J-1502D01*
G01X54350Y281481D01*
X46293Y273424D01*
G02X46075Y273380I-142J141D01*
G01X46018Y273404D01*
X45952Y273503D01*
Y278760D01*
G02X46066Y278941I200J1D01*
G01X46446Y279120D01*
X46560Y279106D01*
X46606Y279069D01*
G03X47561Y278726I955J1158D01*
G03Y281730I0J1502D01*
G03X46606Y281387I0J-1501D01*
G01X46560Y281350D01*
X46446Y281336D01*
X46066Y281515D01*
G02X45952Y281696I86J180D01*
G01Y284816D01*
G02X46010Y284957I200J0D01*
G01X47526Y286474D01*
G03X47952Y287500I-1025J1027D01*
G01Y298816D01*
G02X48010Y298957I200J0D01*
G01X48877Y299824D01*
G02X49018Y299882I141J-142D01*
G01X50355D01*
G02X50528Y299782I0J-200D01*
G01X50728Y299435D01*
Y299329D01*
X50701Y299282D01*
G03X50498Y298528I1299J-754D01*
G03X53502I1502J0D01*
G03X53310Y299263I-1503J0D01*
G01X53286Y299306D01*
X53283Y299402D01*
X53467Y299787D01*
X53543Y299845D01*
X53592Y299853D01*
G03X54845Y301334I-249J1481D01*
G03X53343Y302836I-1502J0D01*
G03X52980Y302791I2J-1502D01*
G01X52956Y302786D01*
X48334D01*
G03X47308Y302360I1J-1451D01*
G01X46628Y301680D01*
G02X46433Y301629I-141J142D01*
G01X46045Y301736D01*
X45970Y301813D01*
X45957Y301866D01*
G03X44500Y303002I-1457J-366D01*
G03Y299998I0J-1502D01*
G03X44620Y300003I-2J1502D01*
G01X44663Y300006D01*
X44744Y299977D01*
X45022Y299705D01*
X45053Y299625D01*
X45051Y299582D01*
G03X45048Y299500I1449J-94D01*
G01Y288184D01*
G02X44990Y288043I-200J0D01*
G01X43474Y286526D01*
G03X43048Y285500I1025J-1027D01*
G01Y273154D01*
X43043Y273130D01*
G03X43015Y272989I1457J-363D01*
G01X43010Y272957D01*
X42981Y272901D01*
X42958Y272877D01*
G02X42675I-141J142D01*
G01X36361Y279191D01*
G03X35335Y279616I-1026J-1026D01*
G01X18319D01*
G02X18178Y279675I1J200D01*
G01X13310Y284543D01*
G02X13252Y284684I142J141D01*
G01Y334058D01*
G02X13324Y334212I200J0D01*
G01X13595Y334437D01*
X13681Y334460D01*
X13725Y334451D01*
G03X14000Y334426I273J1477D01*
G03X15185Y335005I0J1502D01*
G02X15342Y335082I158J-123D01*
G01X15658D01*
G02X15815Y335005I-1J-200D01*
G03X18185I1185J923D01*
G02X18342Y335082I158J-123D01*
G01X18658D01*
G02X18815Y335005I-1J-200D01*
G03X21185I1185J923D01*
G02X21342Y335082I158J-123D01*
G01X21658D01*
G02X21815Y335005I-1J-200D01*
G03X24185I1185J923D01*
G02X24342Y335082I158J-123D01*
G01X24658D01*
G02X24815Y335005I-1J-200D01*
G03X26000Y334426I1185J923D01*
G03Y337430I0J1502D01*
G03X24815Y336851I0J-1502D01*
G02X24658Y336774I-158J123D01*
G01X24342D01*
G02X24185Y336851I1J200D01*
G03X21815I-1185J-923D01*
G02X21658Y336774I-158J123D01*
G01X21342D01*
G02X21185Y336851I1J200D01*
G03X18815I-1185J-923D01*
G02X18658Y336774I-158J123D01*
G01X18342D01*
G02X18185Y336851I1J200D01*
G03X15815I-1185J-923D01*
G02X15658Y336774I-158J123D01*
G01X15342D01*
G02X15185Y336851I1J200D01*
G03X14000Y337430I-1185J-923D01*
G03X13725Y337405I-2J-1502D01*
G01X13681Y337396D01*
X13595Y337419D01*
X13324Y337644D01*
G02X13252Y337798I128J154D01*
G01Y495496D01*
G02X13310Y495637I200J0D01*
G01X17526Y499854D01*
G03X17952Y500880I-1025J1027D01*
G01Y525180D01*
G03X17526Y526206I-1451J-1D01*
G01X16059Y527674D01*
G02X16000Y527816I141J142D01*
G01Y544417D01*
G02X16059Y544559I200J0D01*
G01X23441Y551941D01*
G02X23583Y552000I142J-141D01*
G37*
G36*
G01X15748Y1324772D02*
X187795D01*
G02X201543Y1311024I0J-13748D01*
G01Y15748D01*
G02X187795Y2000I-13748J0D01*
G01X145474D01*
X140740Y6734D01*
Y43307D01*
G03X134000Y50031I-6724J0D01*
G01Y52031D01*
G02X142739Y43307I15J-8724D01*
G01Y7562D01*
X146302Y3999D01*
X187795D01*
G03X199544Y15748I0J11749D01*
G01Y1311024D01*
G03X187795Y1322773I-11749J0D01*
G01X15748D01*
G03X3999Y1311024I0J-11749D01*
G01Y15748D01*
G03X15748Y3999I11749J0D01*
G01X57241D01*
X60804Y7562D01*
Y43307D01*
G02X69500Y52030I8723J0D01*
G01Y50031D01*
G03X62803Y43307I27J-6724D01*
G01Y6734D01*
X58069Y2000D01*
X15748D01*
G02X2000Y15748I0J13748D01*
G01Y1311024D01*
G02X15748Y1324772I13748J0D01*
G37*
G36*
G01Y1321772D02*
X187795D01*
G02X198542Y1311024I-1J-10748D01*
G01Y748743D01*
G02X198342Y748543I-200J0D01*
G01X196093D01*
G02X195951Y748602I0J200D01*
G01X182301Y762252D01*
G02X182242Y762394I141J142D01*
G01Y767799D01*
G02X182301Y767941I200J0D01*
G01X186926Y772567D01*
G03X187352Y773593I-1025J1027D01*
G01Y812200D01*
G03X186926Y813226I-1451J-1D01*
G01X181059Y819094D01*
G02X181000Y819236I141J142D01*
G01Y837409D01*
G03X180941Y837551I-200J0D01*
G01X175551Y842941D01*
G03X175409Y843000I-142J-141D01*
G01X174554D01*
X174528Y843007D01*
G03X171927I-1300J-4779D01*
G01X171902Y843000D01*
X155520D01*
G02X155378Y843059I0J200D01*
G01X153000Y845437D01*
Y850917D01*
G03X152941Y851059I-200J0D01*
G01X150342Y853658D01*
X150321Y853783D01*
X150350Y853841D01*
G03X150502Y854500I-1350J658D01*
G03X149774Y855787I-1502J0D01*
G02X149735Y855817I102J173D01*
G01X143332Y862221D01*
G02X143274Y862362I142J141D01*
G01Y922107D01*
G02X143332Y922248I200J0D01*
G01X164018Y942934D01*
G02X164225Y942982I142J-141D01*
G01X164621Y942844D01*
X164691Y942756D01*
X164698Y942697D01*
G03X164975Y941681I3479J403D01*
G02Y941519I-182J-81D01*
G03X164675Y940100I3202J-1418D01*
G03X171679I3502J0D01*
G03X171379Y941519I-3502J1D01*
G02Y941681I182J81D01*
G03X171679Y943100I-3202J1418D01*
G03X168580Y946579I-3502J0D01*
G01X168521Y946586D01*
X168433Y946656D01*
X168295Y947052D01*
G02X168343Y947259I189J65D01*
G01X176576Y955492D01*
G02X176772Y955543I141J-141D01*
G01X177161Y955433D01*
X177236Y955354D01*
X177248Y955301D01*
G03X177500Y954586I3410J800D01*
G02Y954414I-180J-86D01*
G03X177156Y952900I3158J-1514D01*
G03X180658Y949398I3502J0D01*
G03X182227Y949769I0J3503D01*
G02X182394Y949774I89J-179D01*
G03X183758Y949498I1363J3226D01*
G03X185019Y949733I0J3501D01*
G02X185175Y949727I71J-187D01*
G03X186658Y949398I1482J3173D01*
G03X190160Y952900I0J3502D01*
G03X189816Y954414I-3502J0D01*
G02Y954586I180J86D01*
G03X190160Y956100I-3158J1514D01*
G03X186658Y959602I-3502J0D01*
G03X185397Y959367I0J-3501D01*
G02X185241Y959373I-71J187D01*
G03X183758Y959702I-1482J-3173D01*
G03X182189Y959331I0J-3503D01*
G02X182022Y959326I-89J179D01*
G03X180658Y959602I-1363J-3226D01*
G03X178398Y958775I0J-3502D01*
G01X178353Y958737D01*
X178238Y958721D01*
X177855Y958899D01*
G02X177740Y959080I85J181D01*
G01Y966020D01*
G02X177855Y966201I200J0D01*
G01X178238Y966379D01*
X178353Y966363D01*
X178398Y966325D01*
G03X180658Y965498I2260J2675D01*
G03X182227Y965869I0J3503D01*
G02X182394Y965874I89J-179D01*
G03X183758Y965598I1363J3226D01*
G03X185019Y965833I0J3501D01*
G02X185175Y965827I71J-187D01*
G03X186658Y965498I1482J3173D01*
G03Y972502I0J3502D01*
G03X185397Y972267I0J-3501D01*
G02X185241Y972273I-71J187D01*
G03X183758Y972602I-1482J-3173D01*
G03X182189Y972231I0J-3503D01*
G02X182022Y972226I-89J179D01*
G03X180658Y972502I-1363J-3226D01*
G03X178398Y971675I0J-3502D01*
G01X178353Y971637D01*
X178238Y971621D01*
X177855Y971799D01*
G02X177740Y971980I85J181D01*
G01Y980682D01*
G02X177850Y980861I200J0D01*
G01X178222Y981046D01*
X178334Y981036D01*
X178380Y981001D01*
G03X179285Y980698I905J1200D01*
G03X180470Y981277I0J1502D01*
G02X180627Y981354I158J-123D01*
G01X180943D01*
G02X181100Y981277I-1J-200D01*
G03X183470I1185J923D01*
G02X183627Y981354I158J-123D01*
G01X183943D01*
G02X184100Y981277I-1J-200D01*
G03X186470I1185J923D01*
G02X186627Y981354I158J-123D01*
G01X186943D01*
G02X187100Y981277I-1J-200D01*
G03X188285Y980698I1185J923D01*
G03Y983702I0J1502D01*
G03X187100Y983123I0J-1502D01*
G02X186943Y983046I-158J123D01*
G01X186627D01*
G02X186470Y983123I1J200D01*
G03X184100I-1185J-923D01*
G02X183943Y983046I-158J123D01*
G01X183627D01*
G02X183470Y983123I1J200D01*
G03X181100I-1185J-923D01*
G02X180943Y983046I-158J123D01*
G01X180627D01*
G02X180470Y983123I1J200D01*
G03X179285Y983702I-1185J-923D01*
G03X178380Y983399I0J-1503D01*
G01X178334Y983364D01*
X178222Y983354D01*
X177850Y983539D01*
G02X177740Y983718I90J179D01*
G01Y996105D01*
G02X177798Y996246I200J0D01*
G01X179415Y997864D01*
G03X179840Y998890I-1026J1026D01*
G01Y1004703D01*
G03X179415Y1005729I-1451J0D01*
G01X173132Y1012013D01*
G02X173074Y1012154I142J141D01*
G01Y1015816D01*
G03X172648Y1016842I-1451J-1D01*
G01X170597Y1018893D01*
G03X169571Y1019318I-1026J-1026D01*
G01X158812D01*
G03X157786Y1018893I0J-1451D01*
G01X156293Y1017401D01*
G02X156075Y1017357I-142J141D01*
G01X156018Y1017381D01*
X155952Y1017480D01*
Y1023742D01*
G02X156010Y1023883I200J0D01*
G01X156665Y1024538D01*
G02X156806Y1024596I141J-142D01*
G01X158022D01*
G02X158202Y1024483I0J-200D01*
G01X158383Y1024104D01*
X158369Y1023990D01*
X158332Y1023945D01*
G03X157998Y1023000I1168J-944D01*
G03X159500Y1021498I1502J0D01*
G03X160685Y1022077I0J1502D01*
G02X160842Y1022154I158J-123D01*
G01X161158D01*
G02X161315Y1022077I-1J-200D01*
G03X162500Y1021498I1185J923D01*
G03X164002Y1023000I0J1502D01*
G03X163105Y1024375I-1502J0D01*
G01X163059Y1024395D01*
X162999Y1024470D01*
X162915Y1024888D01*
X162941Y1024980D01*
X162975Y1025016D01*
G03X163386Y1026048I-1090J1032D01*
G03X161884Y1027550I-1502J0D01*
G03X161521Y1027505I2J-1502D01*
G01X161497Y1027500D01*
X156122D01*
G03X155096Y1027074I1J-1451D01*
G01X153474Y1025452D01*
G03X153048Y1024426I1025J-1027D01*
G01Y1013396D01*
G02X152990Y1013255I-200J0D01*
G01X151607Y1011871D01*
G03X151182Y1010845I1026J-1026D01*
G01Y1010387D01*
G02X151123Y1010246I-200J1D01*
G01X148684Y1007807D01*
G02X148504Y1007752I-142J141D01*
G01X148128Y1007827D01*
X148051Y1007890D01*
X148032Y1007937D01*
G03X146644Y1008865I-1388J-574D01*
G03X145142Y1007363I0J-1502D01*
G03X146031Y1005992I1502J0D01*
G01X146076Y1005972D01*
X146136Y1005895D01*
X146216Y1005476D01*
X146188Y1005383D01*
X146154Y1005348D01*
G03X145727Y1004299I1075J-1049D01*
G03X145840Y1003728I1502J1D01*
G01X145859Y1003682D01*
X145849Y1003583D01*
X145636Y1003265D01*
G02X145470Y1003176I-167J111D01*
G01X137870D01*
G02X137707Y1003261I1J200D01*
G03X136482Y1003894I-1225J-869D01*
G03X134980Y1002392I0J-1502D01*
G03X135708Y1001105I1502J0D01*
G01X135729Y1001092D01*
X136123Y1000699D01*
G03X137149Y1000274I1026J1026D01*
G01X148839D01*
G03X149865Y1000699I0J1451D01*
G01X155169Y1006002D01*
G02X155315Y1006061I142J-141D01*
G01X155646Y1006053D01*
X155719Y1006019D01*
X155747Y1005989D01*
G03X156858Y1005498I1111J1011D01*
G03Y1008502I0J1502D01*
G01X156825D01*
X156784Y1008501D01*
X156710Y1008530D01*
X156477Y1008759D01*
G02X156416Y1008902I139J144D01*
G01Y1009051D01*
G02X156475Y1009192I200J-1D01*
G01X157925Y1010643D01*
G03X158350Y1011669I-1026J1026D01*
G01Y1015270D01*
G02X158409Y1015411I200J-1D01*
G01X159355Y1016357D01*
G02X159496Y1016416I142J-141D01*
G01X168887D01*
G02X169028Y1016357I-1J-200D01*
G01X170112Y1015273D01*
G02X170170Y1015132I-142J-141D01*
G01Y1014857D01*
G02X170096Y1014701I-200J-1D01*
G01X169816Y1014477D01*
X169729Y1014456D01*
X169684Y1014466D01*
G03X169358Y1014502I-327J-1466D01*
G03X167856Y1013000I0J-1502D01*
G03X167983Y1012395I1502J-1D01*
G01X168004Y1012349D01*
X167995Y1012249D01*
X167784Y1011925D01*
G02X167617Y1011834I-168J109D01*
G01X166853D01*
G03X165827Y1011409I0J-1451D01*
G01X163921Y1009503D01*
G03X163496Y1008477I1026J-1026D01*
G01Y1007887D01*
X163490Y1007863D01*
G03X163445Y1007500I1457J-365D01*
G03X164662Y1006025I1502J0D01*
G01X164706Y1006017D01*
X164778Y1005965D01*
X164969Y1005617D01*
X164975Y1005529D01*
X164959Y1005487D01*
G03X164856Y1004941I1399J-547D01*
G03X164926Y1004487I1502J-1D01*
G01X164942Y1004438D01*
X164923Y1004339D01*
X164645Y1004000D01*
X164553Y1003962D01*
X164501Y1003968D01*
G03X164337Y1003977I-164J-1493D01*
G03X163050Y1003249I0J-1502D01*
G01X163037Y1003228D01*
X157474Y997664D01*
G03X157204Y997293I1024J-1029D01*
G01X157182Y997249D01*
X157105Y997192D01*
X156685Y997129D01*
X156595Y997159D01*
X156560Y997195D01*
G03X155482Y997651I-1078J-1046D01*
G03Y994647I0J-1502D01*
G03X156403Y994963I-1J1502D01*
G01X156449Y994998D01*
X156562Y995010D01*
X156936Y994826D01*
G02X157048Y994647I-88J-179D01*
G01Y992670D01*
G02X156990Y992529I-200J0D01*
G01X154803Y990341D01*
G03X154378Y989315I1026J-1026D01*
G01Y980084D01*
G02X154266Y979905I-200J1D01*
G01X153894Y979721D01*
X153780Y979732D01*
X153735Y979767D01*
G03X152827Y980075I-911J-1194D01*
G01X152779D01*
X152696Y980117D01*
X152447Y980448D01*
X152431Y980540D01*
X152444Y980585D01*
G03X152502Y981000I-1444J413D01*
G03X149498I-1502J0D01*
G03X150996Y979498I1502J0D01*
G01X151044D01*
X151127Y979456D01*
X151376Y979125D01*
X151392Y979033D01*
X151379Y978988D01*
G03X151321Y978573I1444J-413D01*
G03X152307Y977162I1503J0D01*
G01X152355Y977145D01*
X152422Y977068D01*
X152506Y976689D01*
G02X152452Y976504I-195J-43D01*
G01X152426Y976478D01*
G02X152285Y976420I-141J142D01*
G01X150045D01*
X150021Y976425D01*
G03X149658Y976470I-365J-1457D01*
G03Y973466I0J-1502D01*
G03X150021Y973511I-2J1502D01*
G01X150045Y973516D01*
X152969D01*
G03X153995Y973942I-1J1451D01*
G01X156855Y976802D01*
G03X157280Y977828I-1026J1026D01*
G01Y988631D01*
G02X157339Y988772I200J-1D01*
G01X159526Y990960D01*
G03X159952Y991986I-1025J1027D01*
G01Y995954D01*
G02X160010Y996095I200J0D01*
G01X162456Y998541D01*
G02X162654Y998591I141J-142D01*
G01X163044Y998475D01*
X163119Y998394D01*
X163130Y998340D01*
G03X164600Y997147I1470J309D01*
G03X166102Y998649I0J1502D01*
G03X164909Y1000119I-1502J0D01*
G01X164855Y1000130D01*
X164774Y1000205D01*
X164658Y1000595D01*
G02X164708Y1000793I192J57D01*
G01X165090Y1001175D01*
X165111Y1001188D01*
G03X165839Y1002475I-774J1287D01*
G03X165769Y1002929I-1502J1D01*
G01X165753Y1002978D01*
X165772Y1003077D01*
X166050Y1003416D01*
X166142Y1003454D01*
X166194Y1003448D01*
G03X166358Y1003439I164J1493D01*
G03X167860Y1004941I0J1502D01*
G03X167762Y1005476I-1502J1D01*
G01X167745Y1005519D01*
X167753Y1005609D01*
X167957Y1005957D01*
X168032Y1006007D01*
X168077Y1006014D01*
G03X168267Y1006055I-221J1486D01*
G01X168313Y1006068D01*
X168405Y1006051D01*
X168697Y1005830D01*
G02X168776Y1005670I-121J-159D01*
G01Y996272D01*
G03X169202Y995246I1451J1D01*
G01X170390Y994057D01*
G02X170448Y993916I-142J-141D01*
G01Y965029D01*
G02X170342Y964852I-200J-1D01*
G01X169980Y964660D01*
X169871Y964666D01*
X169824Y964698D01*
G03X167858Y965302I-1966J-2898D01*
G03X166439Y965002I-1J-3502D01*
G02X166277I-81J182D01*
G03X164858Y965302I-1418J-3202D01*
G03Y958298I0J-3502D01*
G03X166277Y958598I1J3502D01*
G02X166439I81J-182D01*
G03X167858Y958298I1418J3202D01*
G03X168162Y958311I3J3502D01*
G01X168225Y958317D01*
X168333Y958254D01*
X168519Y957856D01*
G02X168479Y957630I-181J-84D01*
G01X138208Y927359D01*
G02X138066Y927300I-142J141D01*
G01X137110D01*
G02X136910Y927500I0J200D01*
G01Y951950D01*
G03X136799Y952505I-1452J-2D01*
G01X124734Y981635D01*
G03X124717Y981674I-1339J-560D01*
G01X124700Y981713D01*
Y989617D01*
G02X124759Y989759I200J0D01*
G01X125947Y990947D01*
G02X126088Y991006I142J-141D01*
G01X137887D01*
G02X138065Y990897I0J-200D01*
G01X138254Y990530D01*
X138246Y990419D01*
X138213Y990373D01*
G03X137933Y989500I1221J-873D01*
G03X140937I1502J0D01*
G03X140657Y990373I-1501J0D01*
G01X140624Y990419D01*
X140616Y990530D01*
X140805Y990897D01*
G02X140983Y991006I178J-91D01*
G01X145228D01*
G03X146254Y991431I0J1451D01*
G01X148419Y993596D01*
G03X148844Y994622I-1026J1026D01*
G01Y995262D01*
X148850Y995286D01*
G03X148895Y995649I-1457J365D01*
G03X147678Y997124I-1502J0D01*
G01X147634Y997132D01*
X147562Y997184D01*
X147371Y997532D01*
X147365Y997620D01*
X147381Y997662D01*
G03X147484Y998208I-1399J547D01*
G03X144480I-1502J0D01*
G03X144578Y997673I1502J-1D01*
G01X144595Y997630D01*
X144587Y997540D01*
X144383Y997192D01*
X144308Y997142D01*
X144263Y997135D01*
G03X142980Y995649I219J-1486D01*
G03X143416Y994590I1502J-1D01*
G01X143460Y994547D01*
X143483Y994429D01*
X143317Y994032D01*
G02X143133Y993908I-185J76D01*
G01X123849D01*
G03X122823Y993483I0J-1451D01*
G01X121604Y992265D01*
G02X121414Y992212I-142J141D01*
G01X121029Y992309D01*
X120954Y992381D01*
X120938Y992433D01*
G03X119500Y993502I-1438J-433D01*
G03X118988Y993412I0J-1501D01*
G01X118942Y993395D01*
X118845Y993408D01*
X118537Y993624D01*
G02X118452Y993788I115J164D01*
G01Y1101466D01*
G02X118510Y1101607I200J0D01*
G01X132910Y1116008D01*
G02X132949Y1116038I141J-143D01*
G03X133677Y1117325I-774J1287D01*
G03X132908Y1118636I-1502J0D01*
G01X132867Y1118659D01*
X132814Y1118736D01*
X132764Y1119099D01*
G02X132821Y1119268I198J27D01*
G01X135043Y1121490D01*
G02X135184Y1121548I141J-142D01*
G01X137500D01*
G03X138526Y1121974I-1J1451D01*
G01X152407Y1135855D01*
G03X152832Y1136881I-1026J1026D01*
G01Y1169197D01*
G02X152891Y1169338I200J-1D01*
G01X167232Y1183680D01*
X167377Y1183692D01*
X167437Y1183649D01*
G03X169291Y1183058I1854J2611D01*
G03Y1189462I0J3202D01*
G03X166124Y1186732I0J-3202D01*
G01X166119Y1186700D01*
X166091Y1186644D01*
X150906Y1171459D01*
G02X150764Y1171400I-142J141D01*
G01X149236D01*
G02X149094Y1171459I0J200D01*
G01X143800Y1176753D01*
X143787Y1176774D01*
G03X142500Y1177502I-1287J-774D01*
G03X140998Y1176000I0J-1502D01*
G03X141726Y1174713I1502J0D01*
G01X141747Y1174700D01*
X145082Y1171365D01*
G02Y1171082I-141J-141D01*
G01X144859Y1170859D01*
G03X144800Y1170717I141J-142D01*
G01Y1170183D01*
G03X144859Y1170041I200J0D01*
G01X147171Y1167729D01*
G02X147230Y1167588I-141J-142D01*
G01Y1159789D01*
G02X147105Y1159603I-200J0D01*
G01X146704Y1159441D01*
X146585Y1159466D01*
X146542Y1159510D01*
G03X146526Y1159526I-1034J-1018D01*
G01X143800Y1162253D01*
X143787Y1162274D01*
G03X142500Y1163002I-1287J-774D01*
G03X140998Y1161500I0J-1502D01*
G03X141726Y1160213I1502J0D01*
G02X141765Y1160183I-102J-173D01*
G01X143990Y1157957D01*
G02X144048Y1157816I-142J-141D01*
G01Y1152664D01*
G02X143950Y1152492I-200J0D01*
G01X143607Y1152290D01*
X143501Y1152288D01*
X143455Y1152314D01*
G03X142727Y1152502I-728J-1314D01*
G03Y1149498I0J-1502D01*
G03X143455Y1149686I0J1502D01*
G01X143501Y1149712D01*
X143607Y1149710D01*
X143950Y1149508D01*
G02X144048Y1149336I-102J-172D01*
G01Y1142938D01*
G02X143990Y1142797I-200J0D01*
G01X143495Y1142301D01*
G02X143335Y1142244I-141J142D01*
G01X142985Y1142275D01*
X142908Y1142320D01*
X142883Y1142356D01*
G03X141649Y1143002I-1234J-856D01*
G03X140147Y1141500I0J-1502D01*
G03X140793Y1140266I1502J0D01*
G01X140829Y1140241D01*
X140874Y1140164D01*
X140905Y1139814D01*
G02X140848Y1139654I-199J-19D01*
G01X121352Y1120159D01*
G02X121210Y1120100I-142J141D01*
G01X119183D01*
G02X119041Y1120159I0J200D01*
G01X118510Y1120690D01*
G02X118452Y1120831I142J141D01*
G01Y1137104D01*
G02X118510Y1137245I200J0D01*
G01X119325Y1138060D01*
G02X119550Y1138101I142J-141D01*
G01X119948Y1137919D01*
X120011Y1137812D01*
X120007Y1137749D01*
G03X119998Y1137500I3493J-251D01*
G03X123500Y1141002I3502J0D01*
G03X123251Y1140993I2J-3502D01*
G01X123188Y1140989D01*
X123081Y1141052D01*
X122899Y1141450D01*
G02X122940Y1141675I182J83D01*
G01X125526Y1144262D01*
G03X125952Y1145288I-1025J1027D01*
G01Y1148188D01*
X125957Y1148212D01*
G03X126002Y1148575I-1457J365D01*
G03X124500Y1150077I-1502J0D01*
G03X124273Y1150060I-2J-1502D01*
G01X124230Y1150053D01*
X124146Y1150077D01*
X123882Y1150303D01*
G02X123812Y1150455I130J152D01*
G01Y1160677D01*
G02X123871Y1160818I200J-1D01*
G01X127753Y1164700D01*
X127774Y1164713D01*
G03X128502Y1166000I-774J1287D01*
G03X127655Y1167352I-1503J0D01*
G01X127611Y1167373D01*
X127553Y1167450D01*
X127491Y1167820D01*
G02X127546Y1167995I197J34D01*
G01X129516Y1169965D01*
G03X129942Y1170991I-1025J1027D01*
G01Y1183817D01*
G03X129516Y1184843I-1451J-1D01*
G01X127660Y1186700D01*
X127647Y1186721D01*
G03X126360Y1187449I-1287J-774D01*
G03X124858Y1185947I0J-1502D01*
G03X125586Y1184660I1502J0D01*
G01X125607Y1184647D01*
X126980Y1183274D01*
G02X127038Y1183133I-142J-141D01*
G01Y1177447D01*
G02X126925Y1177266I-200J-1D01*
G01X126546Y1177086D01*
X126432Y1177100D01*
X126386Y1177136D01*
G03X125440Y1177472I-947J-1166D01*
G03Y1174468I0J-1502D01*
G03X126386Y1174804I-1J1502D01*
G01X126432Y1174840D01*
X126546Y1174854D01*
X126925Y1174674D01*
G02X127038Y1174493I-87J-180D01*
G01Y1171675D01*
G02X126980Y1171534I-200J0D01*
G01X119235Y1163788D01*
G03X118810Y1162762I1026J-1026D01*
G01Y1148103D01*
G02X118751Y1147962I-200J1D01*
G01X111724Y1140934D01*
G03X111409Y1140464I1025J-1028D01*
G01X111388Y1140413D01*
X111303Y1140348D01*
X110846Y1140294D01*
X110748Y1140337D01*
X110716Y1140382D01*
G03X109500Y1141002I-1216J-882D01*
G03Y1137998I0J-1502D01*
G03X110604Y1138482I0J1501D01*
G01X110647Y1138528D01*
X110766Y1138556D01*
X111171Y1138397D01*
G02X111298Y1138211I-73J-186D01*
G01Y1121246D01*
G02X111240Y1121105I-200J0D01*
G01X105594Y1115459D01*
G02X105452Y1115400I-142J141D01*
G01X102683D01*
G02X102541Y1115459I0J200D01*
G01X102010Y1115990D01*
G02X101952Y1116131I142J141D01*
G01Y1121259D01*
G03X101526Y1122285I-1451J-1D01*
G01X98917Y1124895D01*
G02X98858Y1125036I141J142D01*
G01Y1157988D01*
G03X98433Y1159014I-1451J0D01*
G01X87510Y1169938D01*
G02X87452Y1170079I142J141D01*
G01Y1176188D01*
X87457Y1176212D01*
G03X87502Y1176575I-1457J365D01*
G03X84498I-1502J0D01*
G03X84543Y1176212I1502J2D01*
G01X84548Y1176188D01*
Y1174031D01*
G02X84490Y1173890I-200J0D01*
G01X83659Y1173059D01*
G02X83517Y1173000I-142J141D01*
G01X81561D01*
G02X81419Y1173059I0J200D01*
G01X80317Y1174160D01*
G02X80287Y1174199I143J141D01*
G03X79000Y1174927I-1287J-774D01*
G03X77498Y1173425I0J-1502D01*
G03X78226Y1172138I1502J0D01*
G01X78247Y1172125D01*
X93797Y1156575D01*
G02X93856Y1156434I-141J-142D01*
G01Y1123482D01*
G03X94281Y1122456I1451J0D01*
G01X96890Y1119846D01*
G02X96948Y1119705I-142J-141D01*
G01Y1116586D01*
G02X96825Y1116401I-200J-1D01*
G01X96768Y1116378D01*
X96651Y1116401D01*
X90510Y1122542D01*
G02X90452Y1122683I142J141D01*
G01Y1151501D01*
G03X90026Y1152527I-1451J-1D01*
G01X84102Y1158451D01*
G03X83076Y1158876I-1026J-1026D01*
G01X79387D01*
X79363Y1158882D01*
G03X79000Y1158927I-365J-1457D01*
G03Y1155923I0J-1502D01*
G03X79363Y1155968I-2J1502D01*
G01X79387Y1155974D01*
X82392D01*
G02X82533Y1155915I-1J-200D01*
G01X87490Y1150958D01*
G02X87548Y1150817I-142J-141D01*
G01Y1121999D01*
G03X87974Y1120973I1451J1D01*
G01X94790Y1114156D01*
G02X94848Y1114015I-142J-141D01*
G01Y1104231D01*
G02X94790Y1104090I-200J0D01*
G01X94259Y1103559D01*
G02X94117Y1103500I-142J141D01*
G01X92636D01*
G02X92494Y1103559I0J200D01*
G01X77844Y1118209D01*
G02Y1118491I142J141D01*
G01X79346Y1119994D01*
G03X79772Y1121020I-1025J1027D01*
G01Y1122180D01*
G03X79346Y1123206I-1451J-1D01*
G01X78526Y1124026D01*
G03X77500Y1124452I-1027J-1025D01*
G01X76340D01*
G03X76235Y1124448I3J-1452D01*
G01X76191Y1124445D01*
X76111Y1124474D01*
X75834Y1124751D01*
X75805Y1124831D01*
X75808Y1124875D01*
G03X75812Y1124980I-1448J108D01*
G01Y1126140D01*
G03X75386Y1127166I-1451J-1D01*
G01X74566Y1127986D01*
G03X73540Y1128412I-1027J-1025D01*
G01X72380D01*
G03X71354Y1127986I1J-1451D01*
G01X69851Y1126484D01*
G02X69569I-141J142D01*
G01X69287Y1126766D01*
G02X69229Y1126929I141J142D01*
G01X69268Y1127284D01*
X69315Y1127361D01*
X69354Y1127386D01*
G03X70045Y1128650I-811J1264D01*
G03X68543Y1130152I-1502J0D01*
G03X67279Y1129461I0J-1502D01*
G01X67254Y1129422D01*
X67177Y1129375D01*
X66822Y1129336D01*
G02X66659Y1129394I-21J199D01*
G01X61108Y1134945D01*
G02X61050Y1135086I142J141D01*
G01Y1138209D01*
G02X61140Y1138377I200J1D01*
G01X61464Y1138588D01*
X61564Y1138596D01*
X61611Y1138575D01*
G03X62216Y1138448I604J1375D01*
G03Y1141452I0J1502D01*
G03X61611Y1141325I-1J-1502D01*
G01X61564Y1141304D01*
X61464Y1141312D01*
X61140Y1141523D01*
G02X61050Y1141691I110J167D01*
G01Y1150439D01*
G02X61108Y1150580I200J0D01*
G01X61228Y1150700D01*
X61249Y1150713D01*
G03X61977Y1152000I-774J1287D01*
G03X60475Y1153502I-1502J0D01*
G03X59188Y1152774I0J-1502D01*
G01X59175Y1152753D01*
X58572Y1152149D01*
G03X58539Y1152116I1009J-1043D01*
G01X58320Y1152203D01*
G02X58194Y1152389I74J186D01*
G01Y1154558D01*
G02X58252Y1154699I200J0D01*
G01X62253Y1158700D01*
X62274Y1158713D01*
G03X63002Y1160000I-774J1287D01*
G03X62697Y1160907I-1501J0D01*
G01X62662Y1160953D01*
X62652Y1161065D01*
X62837Y1161438D01*
G02X63016Y1161548I179J-90D01*
G01X68816D01*
G02X68957Y1161490I0J-200D01*
G01X73958Y1156489D01*
G02X74016Y1156348I-142J-141D01*
G01Y1140200D01*
G03X74442Y1139174I1451J1D01*
G01X76142Y1137474D01*
G03X77109Y1137050I1026J1026D01*
G02X77150Y1137044I-8J-200D01*
G03X77175Y1137038I363J1457D01*
G01X77229Y1136808D01*
G02X77168Y1136612I-195J-47D01*
G03X75998Y1134000I2331J-2612D01*
G03X79500Y1137502I3502J0D01*
G03X79340Y1137498I7J-3502D01*
G01X79290Y1137496D01*
X79202Y1137537D01*
X78943Y1137881D01*
X78927Y1137977D01*
X78943Y1138025D01*
G03X79020Y1138500I-1425J475D01*
G03X79002Y1138730I-1502J-2D01*
G01X79000Y1138745D01*
Y1142405D01*
X79002Y1142420D01*
G03X79020Y1142650I-1484J232D01*
G03X79002Y1142880I-1502J-2D01*
G01X79000Y1142895D01*
Y1146572D01*
G02X79032Y1146681I200J0D01*
G03X79275Y1147500I-1259J819D01*
G03X77773Y1149002I-1502J0D01*
G03X77415Y1148959I-1J-1502D01*
G01X77370Y1148948D01*
X77280Y1148967D01*
X76996Y1149190D01*
G02X76920Y1149347I124J157D01*
G01Y1157032D01*
G03X76494Y1158058I-1451J-1D01*
G01X71207Y1163346D01*
G02X71157Y1163547I141J142D01*
G01X71280Y1163939D01*
X71363Y1164012D01*
X71418Y1164022D01*
G03X72652Y1165500I-268J1478D01*
G03X69648I-1502J0D01*
G03X69853Y1164742I1502J0D01*
G02X69658Y1164443I-173J-100D01*
G03X69500Y1164452I-161J-1443D01*
G01X66213D01*
G02X66049Y1164537I0J200D01*
G01X65833Y1164845D01*
X65820Y1164942D01*
X65837Y1164988D01*
G03X65927Y1165500I-1411J512D01*
G03X62923I-1502J0D01*
G03X63013Y1164988I1501J0D01*
G01X63030Y1164942D01*
X63017Y1164845D01*
X62801Y1164537D01*
G02X62637Y1164452I-164J115D01*
G01X60500D01*
G03X59474Y1164026I1J-1451D01*
G01X53193Y1157746D01*
G02X52975Y1157702I-142J141D01*
G01X52918Y1157726D01*
X52852Y1157825D01*
Y1170215D01*
G02X52910Y1170356I200J0D01*
G01X76026Y1193473D01*
G03X76452Y1194499I-1025J1027D01*
G01Y1196113D01*
X76457Y1196137D01*
G03X76502Y1196500I-1457J365D01*
G03X73498I-1502J0D01*
G03X73543Y1196137I1502J2D01*
G01X73548Y1196113D01*
Y1195183D01*
G02X73490Y1195042I-200J0D01*
G01X59628Y1181179D01*
G02X59433Y1181128I-141J142D01*
G01X59045Y1181235D01*
X58970Y1181312D01*
X58957Y1181365D01*
G03X57500Y1182502I-1457J-365D01*
G03X55998Y1181000I0J-1502D01*
G03X57135Y1179543I1502J0D01*
G01X57188Y1179530D01*
X57265Y1179455D01*
X57372Y1179067D01*
G02X57321Y1178872I-193J-54D01*
G01X50374Y1171925D01*
G03X49948Y1170899I1025J-1027D01*
G01Y1137631D01*
G02X49890Y1137490I-200J0D01*
G01X49159Y1136759D01*
G02X49017Y1136700I-142J141D01*
G01X46578D01*
G02X46436Y1136759I0J200D01*
G01X37343Y1145852D01*
X37316Y1145957D01*
X37331Y1146010D01*
G03X37454Y1146890I-3079J879D01*
G03X34252Y1143688I-3202J0D01*
G03X35132Y1143811I1J3202D01*
G01X35185Y1143826D01*
X35290Y1143799D01*
X44090Y1134999D01*
G02X44148Y1134858I-142J-141D01*
G01Y1133900D01*
G03X44574Y1132874I1451J1D01*
G01X60176Y1117271D01*
G02X60234Y1117130I-142J-141D01*
G01Y1114814D01*
G03X60660Y1113788I1451J1D01*
G01X79313Y1095134D01*
G02X79372Y1094993I-141J-142D01*
G01Y998934D01*
G02X79313Y998793I-200J1D01*
G01X54794Y974273D01*
G03X54368Y973247I1025J-1027D01*
G01Y885703D01*
G02X54230Y885513I-200J0D01*
G01X53806Y885376D01*
X53683Y885416D01*
X53645Y885469D01*
G03X50808Y886917I-2837J-2055D01*
G03X49626Y886711I1J-3502D01*
G02X49490I-68J189D01*
G03X48308Y886917I-1183J-3296D01*
G03X44806Y883415I0J-3502D01*
G03X45106Y881996I3502J-1D01*
G02Y881834I-182J-81D01*
G03X44806Y880415I3202J-1418D01*
G03X45106Y878996I3502J-1D01*
G02Y878834I-182J-81D01*
G03X44806Y877415I3202J-1418D01*
G03X48308Y873913I3502J0D01*
G03X49490Y874119I-1J3502D01*
G02X49626I68J-189D01*
G03X50808Y873913I1183J3296D01*
G03X53645Y875361I0J3503D01*
G01X53683Y875414D01*
X53806Y875454D01*
X54230Y875317D01*
G02X54368Y875127I-62J-190D01*
G01Y851224D01*
G02X54310Y851083I-200J0D01*
G01X40786Y837559D01*
G02X40644Y837500I-142J141D01*
G01X22083D01*
G02X21941Y837559I0J200D01*
G01X17657Y841843D01*
G02X17598Y841985I141J142D01*
G01Y854924D01*
G03X17539Y855066I-200J0D01*
G01X16960Y855645D01*
G02X16902Y855786I142J141D01*
G01Y861667D01*
X16907Y861690D01*
G03X17002Y862500I-3406J810D01*
G03X13500Y866002I-3502J0D01*
G03X12064Y865694I0J-3502D01*
G01X12017Y865673D01*
X11917Y865680D01*
X11591Y865891D01*
G02X11500Y866059I109J168D01*
G01Y868924D01*
G02X11597Y869096I200J1D01*
G01X11938Y869300D01*
X12042Y869302D01*
X12089Y869277D01*
G03X12800Y869098I711J1323D01*
G03X13906Y869583I1J1502D01*
G02X14053Y869648I148J-135D01*
G01X14347D01*
G02X14494Y869583I-1J-200D01*
G03X15600Y869098I1105J1017D01*
G03X17102Y870600I0J1502D01*
G03X16677Y871647I-1502J0D01*
G01X16648Y871677D01*
X16619Y871750D01*
X16628Y872118D01*
X16660Y872190D01*
X16690Y872218D01*
G03X17166Y873315I-1026J1097D01*
G03X16587Y874500I-1502J0D01*
G02X16510Y874657I123J158D01*
G01Y874973D01*
G02X16587Y875130I200J-1D01*
G03Y877500I-923J1185D01*
G02X16510Y877657I123J158D01*
G01Y877973D01*
G02X16587Y878130I200J-1D01*
G03X17166Y879315I-923J1185D01*
G03X15664Y880817I-1502J0D01*
G03X14558Y880332I-1J-1502D01*
G02X14411Y880267I-148J135D01*
G01X14117D01*
G02X13970Y880332I1J200D01*
G03X12864Y880817I-1105J-1017D01*
G03X12103Y880610I0J-1502D01*
G01X12056Y880582D01*
X11949D01*
X11601Y880781D01*
G02X11500Y880955I99J174D01*
G01Y902968D01*
G02X11559Y903110I200J0D01*
G01X11700Y903251D01*
G03X13202Y904753I0J1502D01*
G03X12623Y905938I-1502J0D01*
G02X12546Y906095I123J158D01*
G01Y906411D01*
G02X12623Y906568I200J-1D01*
G03X13202Y907753I-923J1185D01*
G03X11700Y909255I-1502J0D01*
G01X11559Y909396D01*
G02X11500Y909538I141J142D01*
G01Y913968D01*
G02X11559Y914110I200J0D01*
G01X11700Y914251D01*
G03X13202Y915753I0J1502D01*
G03X12623Y916938I-1502J0D01*
G02X12546Y917095I123J158D01*
G01Y917411D01*
G02X12623Y917568I200J-1D01*
G03X13202Y918753I-923J1185D01*
G03X11700Y920255I-1502J0D01*
G01X11559Y920396D01*
G02X11500Y920538I141J142D01*
G01Y923968D01*
G02X11559Y924110I200J0D01*
G01X11700Y924251D01*
G03X13202Y925753I0J1502D01*
G03X12623Y926938I-1502J0D01*
G02X12546Y927095I123J158D01*
G01Y927411D01*
G02X12623Y927568I200J-1D01*
G03X13202Y928753I-923J1185D01*
G03X11700Y930255I-1502J0D01*
G01X11559Y930396D01*
G02X11500Y930538I141J142D01*
G01Y932372D01*
G02X11564Y932519I200J0D01*
G01X11812Y932747D01*
X11890Y932774D01*
X11932Y932771D01*
G03X12053Y932766I122J1497D01*
G03X13555Y934268I0J1502D01*
G03X12976Y935453I-1502J0D01*
G02X12899Y935610I123J158D01*
G01Y935926D01*
G02X12976Y936083I200J-1D01*
G03X13555Y937268I-923J1185D01*
G03X12053Y938770I-1502J0D01*
G03X11932Y938765I1J-1502D01*
G01X11890Y938762D01*
X11812Y938789D01*
X11564Y939017D01*
G02X11500Y939164I136J147D01*
G01Y947433D01*
G03X11441Y947575I-200J0D01*
G01X11160Y947856D01*
G02X11102Y947997I142J141D01*
G01Y953828D01*
G02X11237Y954017I200J0D01*
G01X11656Y954160D01*
X11778Y954124D01*
X11818Y954072D01*
G03X14587Y952714I2769J2144D01*
G03X15788Y952927I-2J3502D01*
G02X15926I69J-188D01*
G03X17127Y952714I1203J3289D01*
G03X18328Y952927I-2J3502D01*
G02X18466I69J-188D01*
G03X19667Y952714I1203J3289D01*
G03X23169Y956216I0J3502D01*
G03X22963Y957398I-3502J-1D01*
G02Y957534I189J68D01*
G03X22991Y957613I-3286J1209D01*
G01X23010Y957670D01*
X23103Y957744D01*
X23587Y957788D01*
X23692Y957732D01*
X23721Y957680D01*
G03X26791Y955863I3070J1685D01*
G03X27992Y956076I-2J3502D01*
G02X28130I69J-188D01*
G03X29331Y955863I1203J3289D01*
G03X30532Y956076I-2J3502D01*
G02X30670I69J-188D01*
G03X31871Y955863I1203J3289D01*
G03X34992Y957777I0J3502D01*
G01X35022Y957835D01*
X35133Y957893D01*
X35635Y957827D01*
X35727Y957741D01*
X35740Y957678D01*
G03X39167Y954898I3427J722D01*
G03X40586Y955198I1J3502D01*
G02X40748I81J-182D01*
G03X42167Y954898I1418J3202D01*
G03X44741Y956026I0J3501D01*
G01X44778Y956065D01*
X44877Y956097D01*
X45319Y956003D01*
X45397Y955934D01*
X45414Y955883D01*
G03X48731Y953505I3317J1124D01*
G03X52233Y957007I0J3502D01*
G03X52027Y958189I-3502J-1D01*
G02Y958325I189J68D01*
G03X52233Y959507I-3296J1183D01*
G03X51960Y960863I-3502J0D01*
G02X51955Y961003I184J77D01*
G03X52133Y962107I-3324J1102D01*
G03X51927Y963289I-3502J-1D01*
G02Y963425I189J68D01*
G03X52133Y964607I-3296J1183D01*
G03X51910Y965837I-3502J0D01*
G02Y965977I187J70D01*
G03X52133Y967207I-3279J1230D01*
G03X51927Y968389I-3502J-1D01*
G02Y968525I189J68D01*
G03X52133Y969707I-3296J1183D01*
G03X51955Y970811I-3502J2D01*
G02X51960Y970951I189J63D01*
G03X52233Y972307I-3229J1356D01*
G03X52027Y973489I-3502J-1D01*
G02Y973625I189J68D01*
G03X52233Y974807I-3296J1183D01*
G03X45229I-3502J0D01*
G03X45435Y973625I3502J1D01*
G02Y973489I-189J-68D01*
G03X45229Y972307I3296J-1183D01*
G03X45407Y971203I3502J-2D01*
G02X45402Y971063I-189J-63D01*
G03X45129Y969707I3229J-1356D01*
G03X45335Y968525I3502J1D01*
G02Y968389I-189J-68D01*
G03X45129Y967207I3296J-1183D01*
G03X45352Y965977I3502J0D01*
G02Y965837I-187J-70D01*
G03X45129Y964607I3279J-1230D01*
G03X45335Y963425I3502J1D01*
G02Y963289I-189J-68D01*
G03X45129Y962107I3296J-1183D01*
G03X45402Y960751I3502J0D01*
G02X45407Y960611I-184J-77D01*
G01Y960609D01*
G02X45250Y960475I-190J63D01*
G01X45138Y960456D01*
G02X44946Y960531I-34J197D01*
G03X42167Y961902I-2779J-2131D01*
G03X40748Y961602I-1J-3502D01*
G02X40586I-81J182D01*
G03X39167Y961902I-1418J-3202D01*
G03X36046Y959988I0J-3502D01*
G01X36016Y959930D01*
X35905Y959872D01*
X35403Y959938D01*
X35311Y960024D01*
X35298Y960087D01*
G03X35167Y960547I-3426J-727D01*
G02Y960683I189J68D01*
G03X35373Y961865I-3296J1183D01*
G03X31871Y965367I-3502J0D01*
G03X30651Y965148I-1J-3502D01*
G02X30511I-70J187D01*
G03X29291Y965367I-1219J-3283D01*
G03X28109Y965161I1J-3502D01*
G02X27973I-68J189D01*
G03X26791Y965367I-1183J-3296D01*
G03X23289Y961865I0J-3502D01*
G03X23495Y960683I3502J1D01*
G02Y960547I-189J-68D01*
G03X23467Y960468I3286J-1209D01*
G01X23448Y960411D01*
X23355Y960337D01*
X22871Y960293D01*
X22766Y960349D01*
X22737Y960401D01*
G03X19667Y962218I-3070J-1685D01*
G03X18447Y961999I-1J-3502D01*
G02X18307I-70J187D01*
G03X17087Y962218I-1219J-3283D01*
G03X15905Y962012I1J-3502D01*
G02X15769I-68J189D01*
G03X14587Y962218I-1183J-3296D01*
G03X11818Y960860I0J-3502D01*
G01X11778Y960808D01*
X11656Y960772D01*
X11237Y960915D01*
G02X11102Y961104I65J189D01*
G01Y973466D01*
G02X11160Y973607I200J0D01*
G01X12870Y975317D01*
G02X13036Y975374I141J-141D01*
G01X13397Y975328D01*
X13473Y975278D01*
X13497Y975237D01*
G03X14791Y974498I1294J763D01*
G03X15438Y974645I-1J1502D01*
G01X15482Y974666D01*
X15578Y974663D01*
X15949Y974458D01*
X16002Y974378D01*
X16008Y974329D01*
G03X17500Y972998I1492J171D01*
G03Y976002I0J1502D01*
G03X16853Y975855I1J-1502D01*
G01X16809Y975834D01*
X16713Y975837D01*
X16342Y976042D01*
X16289Y976122D01*
X16283Y976171D01*
G03X15554Y977294I-1492J-171D01*
G01X15513Y977318D01*
X15463Y977394D01*
X15417Y977755D01*
G02X15474Y977921I198J25D01*
G01X24728Y987176D01*
G03X25154Y988202I-1025J1027D01*
G01Y991874D01*
X25159Y991898D01*
G03X25204Y992261I-1457J365D01*
G03X24156Y993693I-1502J0D01*
G01X24105Y993709D01*
X24033Y993788D01*
X23937Y994234D01*
X23970Y994336D01*
X24011Y994372D01*
G03X24511Y995491I-1002J1119D01*
G03X23655Y996847I-1502J0D01*
G01X23610Y996868D01*
X23552Y996945D01*
X23488Y997316D01*
G02X23544Y997491I197J33D01*
G01X27686Y1001633D01*
G02X27827Y1001692I142J-141D01*
G01X28906D01*
G02X29081Y1001589I0J-200D01*
G01X29278Y1001235D01*
X29275Y1001127D01*
X29246Y1001080D01*
G03X29020Y1000288I1275J-792D01*
G03X29065Y999925I1502J2D01*
G01X29070Y999901D01*
Y997169D01*
G03X29496Y996143I1451J1D01*
G01X30877Y994761D01*
G02X30935Y994609I-141J-141D01*
G01X30918Y994269D01*
X30879Y994195D01*
X30846Y994167D01*
G03X30289Y993000I944J-1167D01*
G03X31791Y991498I1502J0D01*
G03X31948Y991506I2J1502D01*
G01X31991Y991511D01*
X32071Y991485D01*
X32323Y991257D01*
G02X32390Y991108I-133J-149D01*
G01Y978834D01*
G02X32331Y978693I-200J1D01*
G01X30878Y977239D01*
G02X30690Y977186I-141J142D01*
G01X30308Y977276D01*
X30232Y977346D01*
X30215Y977395D01*
G03X28791Y978421I-1424J-475D01*
G03X27616Y977855I0J-1503D01*
G01X27581Y977811D01*
X27480Y977773D01*
X27024Y977853D01*
X26942Y977924D01*
X26924Y977977D01*
G03X25500Y979002I-1424J-477D01*
G03X23998Y977500I0J-1502D01*
G03X25249Y976019I1502J0D01*
G01X25292Y976012D01*
X25364Y975963D01*
X25566Y975629D01*
X25576Y975542D01*
X25562Y975501D01*
G03X25488Y975034I1428J-466D01*
G03X26219Y973745I1502J0D01*
G02X26253Y973719I-104J-171D01*
G03X26505Y973531I989J1063D01*
G01X26541Y973510D01*
X26589Y973444D01*
X26673Y973080D01*
X26658Y973000D01*
X26635Y972965D01*
G03X26384Y972134I1250J-831D01*
G03X29388I1502J0D01*
G03X29250Y972762I-1502J-1D01*
G01X29229Y972809D01*
X29236Y972910D01*
X29445Y973237D01*
G02X29614Y973330I169J-107D01*
G01X30472D01*
G03X31498Y973755I0J1451D01*
G01X34867Y977124D01*
G03X35292Y978150I-1026J1026D01*
G01Y993850D01*
G03X34867Y994876I-1451J0D01*
G01X32032Y997712D01*
G02X31974Y997853I142J141D01*
G01Y999901D01*
X31979Y999925D01*
G03X32024Y1000288I-1457J365D01*
G03X31798Y1001080I-1501J0D01*
G01X31769Y1001127D01*
X31766Y1001235D01*
X31963Y1001589D01*
G02X32138Y1001692I175J-97D01*
G01X33787D01*
G02X33928Y1001633I-1J-200D01*
G01X34758Y1000804D01*
G03X35784Y1000378I1027J1025D01*
G01X65434D01*
G03X66460Y1000804I-1J1451D01*
G01X70555Y1004898D01*
X70576Y1004911D01*
G03X71304Y1006198I-774J1287D01*
G03X69802Y1007700I-1502J0D01*
G03X68515Y1006972I0J-1502D01*
G01X68502Y1006951D01*
X64891Y1003340D01*
G02X64750Y1003282I-141J142D01*
G01X58120D01*
G02X57967Y1003352I-1J200D01*
G01X57741Y1003620D01*
X57718Y1003704D01*
X57726Y1003748D01*
G03X57747Y1004000I-1481J250D01*
G03X54743I-1502J0D01*
G03X54764Y1003748I1502J-2D01*
G01X54772Y1003704D01*
X54749Y1003620D01*
X54523Y1003352D01*
G02X54370Y1003282I-152J130D01*
G01X40432D01*
G02X40248Y1003403I0J200D01*
G01X40080Y1003797D01*
X40102Y1003915D01*
X40143Y1003959D01*
G03X40563Y1005000I-1082J1042D01*
G03X37559I-1502J0D01*
G03X37979Y1003959I1502J1D01*
G01X38020Y1003915D01*
X38042Y1003797D01*
X37874Y1003403D01*
G02X37690Y1003282I-184J79D01*
G01X36468D01*
G02X36327Y1003340I0J200D01*
G01X35497Y1004169D01*
G03X34471Y1004594I-1026J-1026D01*
G01X27143D01*
G03X26117Y1004169I0J-1451D01*
G01X17535Y995587D01*
G03X17220Y995117I1025J-1028D01*
G01X16385Y993100D01*
G02X16161Y992981I-185J77D01*
G01X16090Y992995D01*
X16000Y993105D01*
Y993300D01*
G03X15800Y993500I-200J0D01*
G01X14392D01*
G02X14192Y993700I0J200D01*
G01Y993725D01*
G02X14279Y993890I200J0D01*
G01X14592Y994105D01*
X14689Y994116D01*
X14736Y994098D01*
G03X15275Y993998I539J1403D01*
G03X16777Y995500I0J1502D01*
G03X15890Y996870I-1502J0D01*
G01X15844Y996891D01*
X15784Y996967D01*
X15716Y997341D01*
G02X15771Y997518I196J36D01*
G01X16026Y997774D01*
G03X16452Y998800I-1025J1027D01*
G01Y1000913D01*
X16457Y1000937D01*
G03X16502Y1001300I-1457J365D01*
G03X13498I-1502J0D01*
G03X13543Y1000937I1502J2D01*
G01X13548Y1000913D01*
Y999484D01*
G02X13490Y999343I-200J0D01*
G01X11715Y997567D01*
G03X11290Y996541I1026J-1026D01*
G01Y983925D01*
G02X11231Y983784I-200J1D01*
G01X5342Y977895D01*
G02X5124Y977851I-142J141D01*
G01X5067Y977875D01*
X5000Y977974D01*
Y1311024D01*
G02X15748Y1321772I10748J0D01*
G37*
G36*
G01X41059Y684559D02*
X47707Y691207D01*
G02X47925Y691251I142J-141D01*
G01X47982Y691227D01*
X48048Y691127D01*
Y689000D01*
G03X48474Y687974I1451J1D01*
G01X52697Y683750D01*
G02X52750Y683560I-141J-142D01*
G01X52655Y683176D01*
X52583Y683101D01*
X52533Y683085D01*
G03X51475Y681650I444J-1435D01*
G03X52977Y680148I1502J0D01*
G03X54412Y681206I0J1502D01*
G01X54428Y681256D01*
X54503Y681328D01*
X54887Y681423D01*
G02X55077Y681370I48J-194D01*
G01X60974Y675474D01*
G03X62000Y675048I1027J1025D01*
G01X67613D01*
X67637Y675043D01*
G03X68000Y674998I365J1457D01*
G03X69065Y675441I0J1502D01*
G01X69108Y675484D01*
X69227Y675508D01*
X69625Y675344D01*
G02X69748Y675159I-77J-185D01*
G01Y671615D01*
G02X69676Y671461I-200J0D01*
G01X69405Y671236D01*
X69319Y671213D01*
X69275Y671222D01*
G03X69000Y671247I-273J-1477D01*
G03X67728Y670544I0J-1502D01*
G01X67716Y670525D01*
X67291Y670100D01*
G02X67150Y670042I-141J142D01*
G01X67080D01*
G02X66904Y670147I0J200D01*
G01X66711Y670508D01*
X66717Y670618D01*
X66748Y670664D01*
G03X67002Y671500I-1249J836D01*
G03X63998I-1502J0D01*
G03X64252Y670664I1503J0D01*
G01X64283Y670618D01*
X64289Y670508D01*
X64096Y670147D01*
G02X63920Y670042I-176J95D01*
G01X62077D01*
G03X61051Y669616I1J-1451D01*
G01X54848Y663414D01*
G02X54686Y663356I-142J141D01*
G01X54332Y663392D01*
X54256Y663438D01*
X54231Y663476D01*
G03X52977Y664152I-1254J-825D01*
G03X51475Y662650I0J-1502D01*
G03X52151Y661396I1501J0D01*
G01X52189Y661371D01*
X52235Y661295D01*
X52271Y660941D01*
G02X52213Y660779I-199J-20D01*
G01X40957Y649523D01*
G02X40816Y649464I-142J141D01*
G01X37370D01*
G03X36344Y649039I0J-1451D01*
G01X16774Y629469D01*
G03X16348Y628443I1025J-1027D01*
G01Y566931D01*
G02X16290Y566790I-200J0D01*
G01X14793Y565293D01*
G02X14575Y565249I-142J141D01*
G01X14518Y565273D01*
X14452Y565373D01*
Y629265D01*
G02X14510Y629406I200J0D01*
G01X27897Y642794D01*
G03X28322Y643820I-1026J1026D01*
G01Y647443D01*
G02X28381Y647584I200J-1D01*
G01X28449Y647653D01*
G02X28617Y647710I142J-142D01*
G01X28978Y647662D01*
X29056Y647610D01*
X29079Y647570D01*
G03X30380Y646818I1301J749D01*
G03X31882Y648320I0J1502D01*
G03X31130Y649621I-1501J0D01*
G01X31090Y649644D01*
X31038Y649722D01*
X30990Y650083D01*
G02X31047Y650251I199J26D01*
G01X37926Y657130D01*
G03X38352Y658156I-1025J1027D01*
G01Y685166D01*
G02X38475Y685351I200J0D01*
G01X38532Y685374D01*
X38649Y685351D01*
X39441Y684559D01*
G03X39583Y684500I142J141D01*
G01X40917D01*
G03X41059Y684559I0J200D01*
G37*
G36*
G01X33136Y685000D02*
X35248D01*
G02X35448Y684800I0J-200D01*
G01Y658840D01*
G02X35390Y658699I-200J0D01*
G01X26293Y649602D01*
G02X26075Y649558I-142J141D01*
G01X26018Y649582D01*
X25952Y649681D01*
Y650316D01*
G02X26010Y650457I200J0D01*
G01X31165Y655613D01*
G03X31590Y656639I-1026J1026D01*
G01Y658243D01*
G02X31679Y658410I200J0D01*
G01X31999Y658623D01*
X32097Y658632D01*
X32144Y658613D01*
G03X32720Y658498I576J1387D01*
G03Y661502I0J1502D01*
G03X32144Y661387I0J-1502D01*
G01X32097Y661368D01*
X31999Y661377D01*
X31679Y661590D01*
G02X31590Y661757I111J167D01*
G01Y677247D01*
G02X31680Y677413I200J-1D01*
G01X31999Y677626D01*
X32099Y677635D01*
X32146Y677616D01*
G03X32728Y677498I584J1384D01*
G03Y680502I0J1502D01*
G03X32146Y680384I2J-1502D01*
G01X32099Y680365D01*
X31999Y680374D01*
X31680Y680587D01*
G02X31590Y680753I110J167D01*
G01Y683455D01*
G02X31649Y683596I200J-1D01*
G01X32994Y684941D01*
G02X33136Y685000I142J-141D01*
G37*
G36*
G01X16168Y671115D02*
X22159Y677105D01*
G02X22377Y677148I141J-142D01*
G01X22433Y677125D01*
X22500Y677025D01*
Y675700D01*
G03X22700Y675500I200J0D01*
G01X28488D01*
G02X28688Y675300I0J-200D01*
G01Y657323D01*
G02X28629Y657182I-200J1D01*
G01X23474Y652026D01*
G03X23048Y651000I1025J-1027D01*
G01Y645145D01*
G02X22990Y645004I-200J0D01*
G01X20841Y642855D01*
G02X20623Y642812I-141J142D01*
G01X20567Y642835D01*
X20500Y642935D01*
Y645300D01*
G03X20300Y645500I-200J0D01*
G01X19700D01*
G03X19500Y645300I0J-200D01*
G01Y644083D01*
G02X19441Y643941I-200J0D01*
G01X18983Y643483D01*
G02X18765Y643439I-142J141D01*
G01X18708Y643463D01*
X18642Y643563D01*
Y663059D01*
G02X18700Y663200I200J0D01*
G01X18941Y663441D01*
G03X19000Y663583I-141J142D01*
G01Y667917D01*
G03X18941Y668059I-200J0D01*
G01X16168Y670832D01*
G02Y671115I142J142D01*
G37*
G36*
G01X13083Y749500D02*
X17456D01*
G02X17598Y749441I0J-200D01*
G01X18554Y748485D01*
G02X18612Y748344I-142J-141D01*
G01Y738930D01*
G02X18522Y738763I-200J0D01*
G01X18201Y738551D01*
X18101Y738543D01*
X18054Y738563D01*
G03X17458Y738686I-595J-1379D01*
G03Y735682I0J-1502D01*
G03X18054Y735805I1J1502D01*
G01X18101Y735825D01*
X18201Y735817D01*
X18522Y735605D01*
G02X18612Y735438I-110J-167D01*
G01Y715044D01*
G02X18554Y714903I-200J0D01*
G01X14960Y711309D01*
X14939Y711296D01*
G03X14828Y711223I769J-1290D01*
G02X14559Y711515I-117J162D01*
G03X14927Y712500I-1134J985D01*
G03X13425Y710998I-1502J0D01*
G03X13822Y711051I1J1502D01*
G01X13877Y711067D01*
X13984Y711036D01*
X14302Y710690D01*
X14323Y710581D01*
X14303Y710528D01*
G03X14211Y710009I1410J-518D01*
G03X14268Y709599I1503J0D01*
G01X14276Y709573D01*
Y703200D01*
G02X14076Y703000I-200J0D01*
G01X10083D01*
G02X9941Y703059I0J200D01*
G01X9559Y703441D01*
G02X9500Y703583I141J142D01*
G01Y712948D01*
X9485Y712970D01*
G02X9452Y713081I167J110D01*
G01Y721847D01*
G02X9510Y721988I200J0D01*
G01X11745Y724224D01*
G03X12170Y725250I-1026J1026D01*
G01Y728551D01*
G02X12263Y728719I200J-1D01*
G01X12591Y728928D01*
X12693Y728935D01*
X12740Y728913D01*
G03X13375Y728772I635J1361D01*
G03Y731776I0J1502D01*
G03X12740Y731635I0J-1502D01*
G01X12693Y731613D01*
X12591Y731620D01*
X12263Y731829D01*
G02X12170Y731997I107J169D01*
G01Y748588D01*
G02X12229Y748729I200J-1D01*
G01X12941Y749441D01*
G02X13083Y749500I142J-141D01*
G37*
G36*
G01X58908Y656456D02*
X59159Y656706D01*
G02X59377Y656749I141J-142D01*
G01X59433Y656726D01*
X59500Y656626D01*
Y654435D01*
X59498Y654421D01*
G03X59482Y654210I1436J-215D01*
G01Y651808D01*
G02X59424Y651667I-200J0D01*
G01X58071Y650313D01*
G03X57646Y649287I1026J-1026D01*
G01Y635364D01*
X57615Y635291D01*
X57596Y635272D01*
X56564D01*
G02X56423Y635330I0J200D01*
G01X53414Y638339D01*
G02X53371Y638557I142J141D01*
G01X53394Y638613D01*
X53494Y638680D01*
X53790D01*
G03X53990Y638880I0J200D01*
G01Y644860D01*
G03X53790Y645060I-200J0D01*
G01X53655D01*
G02X53484Y645156I0J200D01*
G01X53280Y645493D01*
X53276Y645597D01*
X53300Y645644D01*
G03X53462Y646311I-1289J666D01*
G01Y653105D01*
G02X53521Y653246I200J-1D01*
G01X56247Y655972D01*
G02X56388Y656030I141J-142D01*
G01X57882D01*
G03X58908Y656456I-1J1451D01*
G37*
G36*
G01X62761Y667138D02*
X63588D01*
G02X63738Y667071I1J-200D01*
G01X63965Y666813D01*
X63990Y666731D01*
X63985Y666688D01*
G03X63973Y666500I1490J-189D01*
G03X64102Y665891I1502J0D01*
G01X64119Y665852D01*
X64120Y665772D01*
X63977Y665427D01*
X63919Y665370D01*
X63880Y665355D01*
G03X63374Y665026I521J-1355D01*
G01X57339Y658992D01*
G02X57198Y658934I-141J142D01*
G01X55704D01*
G03X54678Y658508I1J-1451D01*
G01X50985Y654815D01*
G03X50560Y653789I1026J-1026D01*
G01Y646995D01*
G02X50501Y646854I-200J1D01*
G01X49089Y645442D01*
G02X48948Y645384I-141J142D01*
G01X47390D01*
G02X47240Y645450I-2J200D01*
G01X47013Y645706D01*
X46987Y645786D01*
X46992Y645829D01*
G03X47002Y646000I-1492J173D01*
G03X43998I-1502J0D01*
G03X44008Y645829I1502J2D01*
G01X44013Y645786D01*
X43987Y645706D01*
X43760Y645450D01*
G02X43610Y645384I-148J134D01*
G01X37276D01*
G02X37091Y645507I-1J200D01*
G01X37068Y645564D01*
X37091Y645681D01*
X37913Y646503D01*
G02X38054Y646562I142J-141D01*
G01X41500D01*
G03X42526Y646987I0J1451D01*
G01X62620Y667080D01*
G02X62761Y667138I141J-142D01*
G37*
G36*
G01X53052Y697534D02*
Y710209D01*
G02X53175Y710394I200J1D01*
G01X53232Y710417D01*
X53349Y710394D01*
X66390Y697353D01*
G02X66448Y697212I-142J-141D01*
G01Y686813D01*
G02X66367Y686652I-200J0D01*
G01X66067Y686433D01*
X65974Y686417D01*
X65928Y686432D01*
G03X65475Y686502I-453J-1431D01*
G03Y683498I0J-1502D01*
G03X65928Y683568I0J1501D01*
G01X65974Y683583D01*
X66067Y683567D01*
X66367Y683348D01*
G02X66448Y683187I-119J-161D01*
G01Y680600D01*
G03X66450Y680525I1452J1D01*
G01X66253Y680397D01*
G02X66065Y680381I-109J168D01*
G03X65475Y680502I-591J-1381D01*
G03X63973Y679000I0J-1502D01*
G03X64063Y678488I1501J0D01*
G01X64080Y678442D01*
X64067Y678345D01*
X63851Y678037D01*
G02X63687Y677952I-164J115D01*
G01X62684D01*
G02X62543Y678010I0J200D01*
G01X51010Y689543D01*
G02X50952Y689684I142J141D01*
G01Y694963D01*
G02X51075Y695148I200J1D01*
G01X51132Y695171D01*
X51249Y695148D01*
X58175Y688222D01*
X58188Y688201D01*
G03X59475Y687473I1287J774D01*
G03X60977Y688975I0J1502D01*
G03X60249Y690262I-1502J0D01*
G01X60228Y690275D01*
X53110Y697393D01*
G02X53052Y697534I142J141D01*
G37*
G36*
G01X55559Y837559D02*
X58159Y840159D01*
G02X58377Y840202I141J-142D01*
G01X58433Y840179D01*
X58500Y840079D01*
X58579Y840000D01*
X80952D01*
G02X81152Y839800I0J-200D01*
G01Y834916D01*
G02X81075Y834758I-200J0D01*
G03Y832392I924J-1183D01*
G01X81112Y832363D01*
X81152Y832280D01*
Y832077D01*
G02X80952Y831877I-200J0D01*
G01X80926D01*
X80901Y831884D01*
G03X80000Y832002I-901J-3384D01*
G03X76498Y828500I0J-3502D01*
G03X76658Y827454I3502J0D01*
G01X76671Y827412D01*
X76661Y827329D01*
X76462Y826997D01*
X76393Y826949D01*
X76350Y826941D01*
G03X73498Y823500I650J-3441D01*
G03X80502I3502J0D01*
G03X80342Y824546I-3502J0D01*
G01X80329Y824588D01*
X80339Y824671D01*
X80538Y825003D01*
X80607Y825051D01*
X80650Y825059D01*
G03X80675Y825064I-674J3436D01*
G01X80720Y825072D01*
X80805Y825051D01*
X81079Y824826D01*
G02X81152Y824671I-127J-155D01*
G01Y819536D01*
G02X81093Y819394I-200J0D01*
G01X80773Y819074D01*
G02X80631Y819015I-142J141D01*
G01X80604D01*
X74413Y812824D01*
G03X74354Y812682I141J-142D01*
G01Y807990D01*
G02X74295Y807848I-200J0D01*
G01X73974Y807526D01*
G03X73548Y806500I1025J-1027D01*
G01Y800884D01*
G02X73490Y800743I-200J0D01*
G01X72574Y799826D01*
G03X72148Y798800I1025J-1027D01*
G01Y777884D01*
G02X72090Y777743I-200J0D01*
G01X70674Y776326D01*
G03X70248Y775300I1025J-1027D01*
G01Y773031D01*
G02X70190Y772890I-200J0D01*
G01X70028Y772728D01*
X69888Y772714D01*
X69827Y772754D01*
G03X69000Y773002I-827J-1255D01*
G03X67713Y772274I0J-1502D01*
G01X67700Y772253D01*
X65474Y770026D01*
G03X65048Y769000I1025J-1027D01*
G01Y752622D01*
G03X65474Y751596I1451J1D01*
G01X67038Y750031D01*
G02X67096Y749890I-142J-141D01*
G01Y736032D01*
G02X66987Y735854I-200J0D01*
G01X66618Y735667D01*
X66506Y735676D01*
X66460Y735710D01*
G03X65570Y736002I-890J-1210D01*
G03Y732998I0J-1502D01*
G03X66460Y733290I0J1502D01*
G01X66506Y733324D01*
X66618Y733333D01*
X66987Y733146D01*
G02X67096Y732968I-91J-178D01*
G01Y726549D01*
G03X67522Y725523I1451J1D01*
G01X69506Y723538D01*
G02X69564Y723397I-142J-141D01*
G01Y722576D01*
G02X69458Y722400I-200J0D01*
G01X69097Y722207D01*
X68987Y722213D01*
X68941Y722245D01*
G03X68100Y722502I-840J-1245D01*
G03Y719498I0J-1502D01*
G03X68941Y719755I1J1502D01*
G01X68987Y719787D01*
X69097Y719793D01*
X69458Y719600D01*
G02X69564Y719424I-94J-176D01*
G01Y717484D01*
G03X69990Y716458I1451J1D01*
G01X71005Y715442D01*
G02X71064Y715300I-141J-142D01*
G01Y713315D01*
G02X70943Y713131I-200J0D01*
G01X70548Y712963D01*
X70432Y712984D01*
X70388Y713026D01*
G03X69350Y713442I-1038J-1087D01*
G03X68160Y712856I0J-1501D01*
G01X68133Y712822D01*
X68058Y712782D01*
X67715Y712759D01*
G02X67560Y712818I-13J200D01*
G01X54310Y726068D01*
G02X54252Y726209I142J141D01*
G01Y813113D01*
X54257Y813137D01*
G03X54302Y813500I-1457J365D01*
G03X52800Y815002I-1502J0D01*
G03X52367Y814938I1J-1502D01*
G01X52321Y814924D01*
X52228Y814941D01*
X51932Y815161D01*
G02X51852Y815321I120J160D01*
G01Y834826D01*
G02X51910Y834967I200J0D01*
G01X54384Y837441D01*
G02X54526Y837500I142J-141D01*
G01X55417D01*
G03X55559Y837559I0J200D01*
G37*
G36*
G01X114083Y752800D02*
X116117D01*
G02X116259Y752741I0J-200D01*
G01X120049Y748951D01*
X120074Y748906D01*
X120081Y748879D01*
G03X120762Y747966I1455J375D01*
G01X120783Y747953D01*
X123990Y744746D01*
G02X124048Y744605I-142J-141D01*
G01Y728131D01*
G03X124474Y727105I1451J1D01*
G01X126765Y724813D01*
X126778Y724792D01*
G03X128065Y724064I1287J774D01*
G03X128428Y724109I-2J1502D01*
G01X128452Y724114D01*
X129013D01*
G02X129154Y724056I0J-200D01*
G01X140390Y712820D01*
G02X140448Y712679I-142J-141D01*
G01Y697031D01*
G02X140390Y696890I-200J0D01*
G01X139559Y696059D01*
G02X139417Y696000I-142J141D01*
G01X128073D01*
G03X128000Y696002I-78J-1500D01*
G03X127927Y696000I5J-1502D01*
G01X124683D01*
G02X124541Y696059I0J200D01*
G01X123410Y697190D01*
G02X123352Y697331I142J141D01*
G01Y713634D01*
G02X123474Y713818I200J0D01*
G01X123868Y713985D01*
X123986Y713963D01*
X124030Y713921D01*
G03X125075Y713498I1045J1079D01*
G03Y716502I0J1502D01*
G03X124030Y716079I0J-1502D01*
G01X123986Y716037D01*
X123868Y716015D01*
X123474Y716182D01*
G02X123352Y716366I78J184D01*
G01Y716880D01*
G03X122926Y717906I-1451J-1D01*
G01X122059Y718774D01*
G02X122000Y718916I141J142D01*
G01Y718917D01*
G03X121941Y719059I-200J0D01*
G01X111546Y729454D01*
G02X111488Y729595I142J141D01*
G01Y751030D01*
G02X111611Y751215I200J0D01*
G01X111668Y751238D01*
X111785Y751215D01*
X112000Y751304D01*
Y752000D01*
G02X112200Y752200I200J0D01*
G01X113317D01*
G03X113459Y752259I0J200D01*
G01X113941Y752741D01*
G02X114083Y752800I142J-141D01*
G37*
G36*
G01X132538Y841898D02*
Y855222D01*
G02X132662Y855407I200J0D01*
G01X132719Y855430D01*
X132836Y855407D01*
X145441Y842802D01*
G02X145500Y842660I-141J-142D01*
G01Y839702D01*
X145407Y839591D01*
X145335Y839578D01*
G03X144098Y838100I264J-1478D01*
G03X145220Y836647I1502J0D01*
G01X145246Y836640D01*
X145291Y836614D01*
X153616Y828289D01*
G02X153674Y828148I-142J-141D01*
G01Y771374D01*
G03X154100Y770348I1451J1D01*
G01X166175Y758272D01*
G02X166233Y758119I-142J-141D01*
G01X166214Y757778D01*
X166175Y757703D01*
X166141Y757676D01*
G03X165573Y756500I933J-1176D01*
G03X167075Y754998I1502J0D01*
G03X168251Y755566I0J1501D01*
G01X168278Y755600D01*
X168353Y755639D01*
X168694Y755658D01*
G02X168847Y755600I12J-200D01*
G01X171142Y753305D01*
G02X171200Y753149I-141J-141D01*
G01X171176Y752804D01*
X171135Y752729D01*
X171099Y752702D01*
G03X170498Y751500I901J-1202D01*
G03X172000Y749998I1502J0D01*
G03X173202Y750599I0J1503D01*
G01X173229Y750635D01*
X173304Y750676D01*
X173649Y750700D01*
G02X173805Y750642I15J-199D01*
G01X173990Y750457D01*
G02X174048Y750316I-142J-141D01*
G01Y706184D01*
G02X173990Y706043I-200J0D01*
G01X169874Y701926D01*
G03X169448Y700900I1025J-1027D01*
G01Y683497D01*
G02X169321Y683311I-200J0D01*
G01X168915Y683154D01*
X168795Y683182D01*
X168753Y683228D01*
G03X167642Y683719I-1111J-1011D01*
G03Y680715I0J-1502D01*
G03X168753Y681206I0J1502D01*
G01X168795Y681252D01*
X168915Y681280D01*
X169321Y681123D01*
G02X169448Y680937I-73J-186D01*
G01Y675574D01*
G02X169323Y675388I-200J-1D01*
G01X168922Y675226D01*
X168804Y675252D01*
X168761Y675296D01*
G03X167679Y675756I-1082J-1043D01*
G03Y672752I0J-1502D01*
G03X169064Y673673I0J1502D01*
G01X169088Y673729D01*
X169188Y673796D01*
X169248D01*
G02X169448Y673596I0J-200D01*
G01Y673075D01*
G03X169874Y672049I1451J1D01*
G01X174175Y667747D01*
X174188Y667726D01*
G03X175475Y666998I1287J774D01*
G03X176977Y668500I0J1502D01*
G03X176249Y669787I-1502J0D01*
G01X176228Y669800D01*
X175371Y670657D01*
G02Y670939I142J141D01*
G01X175399Y670968D01*
X175471Y670998D01*
X175511D01*
G03X175573Y671000I-17J1502D01*
G01X178363D01*
G02X178505Y670941I0J-200D01*
G01X178990Y670456D01*
G02X179048Y670315I-142J-141D01*
G01Y653184D01*
G02X178990Y653043I-200J0D01*
G01X176457Y650510D01*
G02X176316Y650452I-141J142D01*
G01X173684D01*
G02X173543Y650510I0J200D01*
G01X165538Y658515D01*
G02X165480Y658656I142J141D01*
G01Y661719D01*
G02X165566Y661883I200J0D01*
G01X165877Y662099D01*
X165973Y662111D01*
X166020Y662094D01*
G03X166547Y661998I528J1406D01*
G03Y665002I0J1502D01*
G03X166020Y664906I1J-1502D01*
G01X165973Y664889D01*
X165877Y664901D01*
X165566Y665117D01*
G02X165480Y665281I114J164D01*
G01Y687343D01*
G02X165537Y687483I200J0D01*
G03X165952Y688499I-1036J1016D01*
G01Y690735D01*
G02X166039Y690901I200J1D01*
G01X166356Y691114D01*
X166454Y691125D01*
X166500Y691106D01*
G03X167060Y690998I559J1394D01*
G03Y694002I0J1502D01*
G03X166500Y693894I-1J-1502D01*
G01X166454Y693875D01*
X166356Y693886D01*
X166039Y694099D01*
G02X165952Y694265I113J165D01*
G01Y739810D01*
G03X165526Y740836I-1451J-1D01*
G01X151920Y754443D01*
G02X151863Y754613I141J142D01*
G01X151917Y754978D01*
X151971Y755055D01*
X152013Y755078D01*
G03X152802Y756400I-713J1322D01*
G03X151300Y757902I-1502J0D01*
G03X149978Y757113I0J-1502D01*
G01X149955Y757071D01*
X149878Y757017D01*
X149513Y756963D01*
G02X149343Y757020I-28J198D01*
G01X144986Y761377D01*
G02X144935Y761573I141J141D01*
G01X145045Y761962D01*
X145122Y762036D01*
X145176Y762049D01*
G03X146329Y763510I-349J1461D01*
G03X144827Y765012I-1502J0D01*
G03X143366Y763859I0J-1502D01*
G01X143353Y763805D01*
X143279Y763728D01*
X142890Y763618D01*
G02X142694Y763669I-55J192D01*
G01X134456Y771906D01*
G02X134406Y772104I142J141D01*
G01X134520Y772494D01*
X134599Y772568D01*
X134653Y772580D01*
G03X137402Y776000I-753J3420D01*
G03X133900Y779502I-3502J0D01*
G03X131537Y778585I0J-3503D01*
G01X131505Y778555D01*
X131424Y778529D01*
X131037Y778572D01*
X130964Y778616D01*
X130939Y778652D01*
G03X129705Y779298I-1234J-856D01*
G03X128441Y778608I0J-1503D01*
G01X128416Y778569D01*
X128340Y778522D01*
X127985Y778484D01*
G02X127822Y778541I-22J199D01*
G01X126654Y779709D01*
G02X126596Y779850I142J141D01*
G01Y782613D01*
X126626Y782686D01*
X126645Y782706D01*
X130437D01*
G03X131463Y783131I0J1451D01*
G01X133396Y785064D01*
G03X133822Y786090I-1025J1027D01*
G01Y788485D01*
X133827Y788509D01*
G03X133872Y788872I-1457J365D01*
G03X130868I-1502J0D01*
G03X130913Y788509I1502J2D01*
G01X130918Y788485D01*
Y786774D01*
G02X130860Y786633I-200J0D01*
G01X130671Y786444D01*
G02X130464Y786396I-142J141D01*
G01X130070Y786533D01*
X129998Y786621D01*
X129991Y786679D01*
G03X128500Y788002I-1491J-179D01*
G03X128137Y787957I2J-1502D01*
G01X128113Y787952D01*
X124579D01*
G03X124047Y787850I3J-1452D01*
G01X124000Y787832D01*
X123902Y787843D01*
X123587Y788057D01*
G02X123500Y788222I113J165D01*
G01Y788911D01*
G02X123559Y789053I200J0D01*
G01X128996Y794490D01*
G02X129137Y794548I141J-142D01*
G01X130679D01*
G02X130850Y794451I0J-200D01*
G01X131054Y794109D01*
X131056Y794005D01*
X131030Y793958D01*
G03X130848Y793241I1321J-717D01*
G03X133852I1502J0D01*
G03X133670Y793958I-1503J0D01*
G01X133644Y794005D01*
X133646Y794109D01*
X133850Y794451D01*
G02X134021Y794548I171J-103D01*
G01X143766D01*
G03X144792Y794974I-1J1451D01*
G01X148515Y798697D01*
G03X148940Y799723I-1026J1026D01*
G01Y824812D01*
G03X148515Y825838I-1451J0D01*
G01X132597Y841757D01*
G02X132538Y841898I141J142D01*
G37*
%LPC*%
G75*
G36*
G01X24347Y69451D02*
X24406Y69890D01*
X24369Y69986D01*
X24329Y70019D01*
G02X23176Y72480I2050J2461D01*
G02X29580I3202J0D01*
G02X28427Y70019I-3203J0D01*
G01X28387Y69986D01*
X28350Y69890D01*
X28409Y69451D01*
X28471Y69369D01*
X28518Y69347D01*
G02X31119Y66746I-2140J-4741D01*
G01X31141Y66699D01*
X31223Y66637D01*
X31662Y66578D01*
X31758Y66615D01*
X31791Y66655D01*
G02X34252Y67808I2461J-2050D01*
G02Y61404I0J-3202D01*
G02X31791Y62557I0J3203D01*
G01X31758Y62597D01*
X31662Y62634D01*
X31223Y62575D01*
X31141Y62513D01*
X31119Y62466D01*
G02X28518Y59865I-4741J2140D01*
G01X28471Y59843D01*
X28409Y59761D01*
X28350Y59322D01*
X28387Y59226D01*
X28427Y59193D01*
G02X29580Y56732I-2050J-2461D01*
G02X23176I-3202J0D01*
G02X24329Y59193I3203J0D01*
G01X24369Y59226D01*
X24406Y59322D01*
X24347Y59761D01*
X24285Y59843D01*
X24238Y59865D01*
G02Y69347I2139J4741D01*
G01X24285Y69369D01*
X24347Y69451D01*
G37*
G36*
G01X167260Y77325D02*
X167319Y77764D01*
X167282Y77860D01*
X167242Y77893D01*
G02X166089Y80354I2050J2461D01*
G02X172493I3202J0D01*
G02X171340Y77893I-3203J0D01*
G01X171300Y77860D01*
X171263Y77764D01*
X171322Y77325D01*
X171384Y77243D01*
X171431Y77221D01*
G02X174032Y74620I-2140J-4741D01*
G01X174054Y74573D01*
X174136Y74511D01*
X174575Y74452D01*
X174671Y74489D01*
X174704Y74529D01*
G02X177165Y75682I2461J-2050D01*
G02X180367Y72480I0J-3202D01*
G02X179214Y70019I-3203J0D01*
G01X179174Y69986D01*
X179137Y69890D01*
X179196Y69451D01*
X179258Y69369D01*
X179305Y69347D01*
G02Y59865I-2139J-4741D01*
G01X179258Y59843D01*
X179196Y59761D01*
X179137Y59322D01*
X179174Y59226D01*
X179214Y59193D01*
G02X180367Y56732I-2050J-2461D01*
G02X173963I-3202J0D01*
G02X175116Y59193I3203J0D01*
G01X175156Y59226D01*
X175193Y59322D01*
X175134Y59761D01*
X175072Y59843D01*
X175025Y59865D01*
G02X172424Y62466I2140J4741D01*
G01X172402Y62513D01*
X172320Y62575D01*
X171881Y62634D01*
X171785Y62597D01*
X171752Y62557D01*
G02X169291Y61404I-2461J2050D01*
G02X166089Y64606I0J3202D01*
G02X167242Y67067I3203J0D01*
G01X167282Y67100D01*
X167319Y67196D01*
X167260Y67635D01*
X167198Y67717D01*
X167151Y67739D01*
G02Y77221I2139J4741D01*
G01X167198Y77243D01*
X167260Y77325D01*
G37*
G36*
G01X24347Y93073D02*
X24406Y93512D01*
X24369Y93608D01*
X24329Y93641D01*
G02X23176Y96102I2050J2461D01*
G02X29580I3202J0D01*
G02X28427Y93641I-3203J0D01*
G01X28387Y93608D01*
X28350Y93512D01*
X28409Y93073D01*
X28471Y92991D01*
X28518Y92969D01*
G02X31119Y90368I-2140J-4741D01*
G01X31141Y90321D01*
X31223Y90259D01*
X31662Y90200D01*
X31758Y90237D01*
X31791Y90277D01*
G02X34252Y91430I2461J-2050D01*
G02X37454Y88228I0J-3202D01*
G02X36301Y85767I-3203J0D01*
G01X36261Y85734D01*
X36224Y85638D01*
X36283Y85199D01*
X36345Y85117D01*
X36392Y85095D01*
G02Y75613I-2139J-4741D01*
G01X36345Y75591D01*
X36283Y75509D01*
X36224Y75070D01*
X36261Y74974D01*
X36301Y74941D01*
G02X37454Y72480I-2050J-2461D01*
G02X31050I-3202J0D01*
G02X32203Y74941I3203J0D01*
G01X32243Y74974D01*
X32280Y75070D01*
X32221Y75509D01*
X32159Y75591D01*
X32112Y75613D01*
G02X29511Y78214I2140J4741D01*
G01X29489Y78261D01*
X29407Y78323D01*
X28968Y78382D01*
X28872Y78345D01*
X28839Y78305D01*
G02X26378Y77152I-2461J2050D01*
G02X23176Y80354I0J3202D01*
G02X24329Y82815I3203J0D01*
G01X24369Y82848D01*
X24406Y82944D01*
X24347Y83383D01*
X24285Y83465D01*
X24238Y83487D01*
G02Y92969I2139J4741D01*
G01X24285Y92991D01*
X24347Y93073D01*
G37*
G36*
G01X175134D02*
X175193Y93512D01*
X175156Y93608D01*
X175116Y93641D01*
G02X173963Y96102I2050J2461D01*
G02X180367I3202J0D01*
G02X179214Y93641I-3203J0D01*
G01X179174Y93608D01*
X179137Y93512D01*
X179196Y93073D01*
X179258Y92991D01*
X179305Y92969D01*
G02Y83487I-2139J-4741D01*
G01X179258Y83465D01*
X179196Y83383D01*
X179137Y82944D01*
X179174Y82848D01*
X179214Y82815D01*
G02X180367Y80354I-2050J-2461D01*
G02X173963I-3202J0D01*
G02X175116Y82815I3203J0D01*
G01X175156Y82848D01*
X175193Y82944D01*
X175134Y83383D01*
X175072Y83465D01*
X175025Y83487D01*
G02X172424Y86088I2140J4741D01*
G01X172402Y86135D01*
X172320Y86197D01*
X171881Y86256D01*
X171785Y86219D01*
X171752Y86179D01*
G02X169291Y85026I-2461J2050D01*
G02Y91430I0J3202D01*
G02X171752Y90277I0J-3203D01*
G01X171785Y90237D01*
X171881Y90200D01*
X172320Y90259D01*
X172402Y90321D01*
X172424Y90368D01*
G02X175025Y92969I4741J-2140D01*
G01X175072Y92991D01*
X175134Y93073D01*
G37*
G36*
G01X41157Y148340D02*
G02X40897Y149664I3241J1324D01*
G02X41103Y150846I3502J-1D01*
G03Y150982I-189J68D01*
G02X40897Y152164I3296J1183D01*
G02X44399Y155666I3502J0D01*
G02X45818Y155366I1J-3502D01*
G03X45980I81J182D01*
G02X47399Y155666I1418J-3202D01*
G02X50901Y152164I0J-3502D01*
G02X50695Y150982I-3502J1D01*
G03Y150846I189J-68D01*
G02X50901Y149664I-3296J-1183D01*
G02X50641Y148340I-3501J0D01*
G03Y148188I185J-76D01*
G02X50901Y146864I-3241J-1324D01*
G02X47399Y143362I-3502J0D01*
G02X45980Y143662I-1J3502D01*
G03X45818I-81J-182D01*
G02X44399Y143362I-1418J3202D01*
G02X40897Y146864I0J3502D01*
G02X41157Y148188I3501J0D01*
G03Y148340I-185J76D01*
G37*
G36*
G01X192637Y156406D02*
X192301D01*
X192234Y156381D01*
X192206Y156357D01*
G02X191219Y155987I-987J1131D01*
G02Y158991I0J1502D01*
G02X192206Y158621I0J-1501D01*
G01X192234Y158597D01*
X192301Y158572D01*
X192637D01*
X192704Y158597D01*
X192732Y158621D01*
G02X193719Y158991I987J-1131D01*
G02Y155987I0J-1502D01*
G02X192732Y156357I0J1501D01*
G01X192704Y156381D01*
X192637Y156406D01*
G37*
G36*
G01X8062Y161585D02*
Y161901D01*
G03X7985Y162058I-200J-1D01*
G02X7406Y163243I923J1185D01*
G02X10410I1502J0D01*
G02X9831Y162058I-1502J0D01*
G03X9754Y161901I123J-158D01*
G01Y161585D01*
G03X9831Y161428I200J1D01*
G02X10410Y160243I-923J-1185D01*
G02X7406I-1502J0D01*
G02X7985Y161428I1502J0D01*
G03X8062Y161585I-123J158D01*
G37*
G36*
G01X188818Y172185D02*
Y172501D01*
G03X188741Y172658I-200J-1D01*
G02X188162Y173843I923J1185D01*
G02X189664Y175345I1502J0D01*
G02X190651Y174975I0J-1501D01*
G01X190679Y174951D01*
X190746Y174926D01*
X191082D01*
X191149Y174951D01*
X191177Y174975D01*
G02X192164Y175345I987J-1131D01*
G02X193666Y173843I0J-1502D01*
G02X193087Y172658I-1502J0D01*
G03X193010Y172501I123J-158D01*
G01Y172185D01*
G03X193087Y172028I200J1D01*
G02Y169658I-923J-1185D01*
G03X193010Y169501I123J-158D01*
G01Y169185D01*
G03X193087Y169028I200J1D01*
G02Y166658I-923J-1185D01*
G03X193010Y166501I123J-158D01*
G01Y166185D01*
G03X193087Y166028I200J1D01*
G02X193666Y164843I-923J-1185D01*
G02X192164Y163341I-1502J0D01*
G02X191177Y163711I0J1501D01*
G01X191149Y163735D01*
X191082Y163760D01*
X190746D01*
X190679Y163735D01*
X190651Y163711D01*
G02X189664Y163341I-987J1131D01*
G02X188162Y164843I0J1502D01*
G02X188741Y166028I1502J0D01*
G03X188818Y166185I-123J158D01*
G01Y166501D01*
G03X188741Y166658I-200J-1D01*
G02Y169028I923J1185D01*
G03X188818Y169185I-123J158D01*
G01Y169501D01*
G03X188741Y169658I-200J-1D01*
G02Y172028I923J1185D01*
G03X188818Y172185I-123J158D01*
G37*
G36*
G01X10362Y172285D02*
Y172601D01*
G03X10285Y172758I-200J-1D01*
G02X9706Y173943I923J1185D01*
G02X11208Y175445I1502J0D01*
G02X12195Y175075I0J-1501D01*
G01X12223Y175051D01*
X12290Y175026D01*
X12626D01*
X12693Y175051D01*
X12721Y175075D01*
G02X13708Y175445I987J-1131D01*
G02X15210Y173943I0J-1502D01*
G02X14631Y172758I-1502J0D01*
G03X14554Y172601I123J-158D01*
G01Y172285D01*
G03X14631Y172128I200J1D01*
G02X15210Y170943I-923J-1185D01*
G02X13708Y169441I-1502J0D01*
G02X12721Y169811I0J1501D01*
G01X12693Y169835D01*
X12626Y169860D01*
X12290D01*
X12223Y169835D01*
X12195Y169811D01*
G02X11208Y169441I-987J1131D01*
G02X9706Y170943I0J1502D01*
G02X10285Y172128I1502J0D01*
G03X10362Y172285I-123J158D01*
G37*
G36*
G01X45906Y168062D02*
G02X44487Y167762I-1418J3202D01*
G02X40985Y171264I0J3502D01*
G02X41285Y172683I3502J1D01*
G03Y172845I-182J81D01*
G02X40985Y174264I3202J1418D01*
G02X44487Y177766I3502J0D01*
G02X45906Y177466I1J-3502D01*
G03X46068I81J182D01*
G02X47487Y177766I1418J-3202D01*
G02X50989Y174264I0J-3502D01*
G02X50689Y172845I-3502J-1D01*
G03Y172683I182J-81D01*
G02X50989Y171264I-3202J-1418D01*
G02X47487Y167762I-3502J0D01*
G02X46068Y168062I-1J3502D01*
G03X45906I-81J-182D01*
G37*
G36*
G01X12234Y180685D02*
Y181001D01*
G03X12157Y181158I-200J-1D01*
G02X11578Y182343I923J1185D01*
G02X14582I1502J0D01*
G02X14003Y181158I-1502J0D01*
G03X13926Y181001I123J-158D01*
G01Y180685D01*
G03X14003Y180528I200J1D01*
G02X14582Y179343I-923J-1185D01*
G02X11578I-1502J0D01*
G02X12157Y180528I1502J0D01*
G03X12234Y180685I-123J158D01*
G37*
G36*
G01X186118Y187385D02*
Y187701D01*
G03X186041Y187858I-200J-1D01*
G02X185462Y189043I923J1185D01*
G02X188466I1502J0D01*
G02X187887Y187858I-1502J0D01*
G03X187810Y187701I123J-158D01*
G01Y187385D01*
G03X187887Y187228I200J1D01*
G02X188466Y186043I-923J-1185D01*
G02X185462I-1502J0D01*
G02X186041Y187228I1502J0D01*
G03X186118Y187385I-123J158D01*
G37*
G36*
G01X12234Y191185D02*
Y191501D01*
G03X12157Y191658I-200J-1D01*
G02X11578Y192843I923J1185D01*
G02X14582I1502J0D01*
G02X14003Y191658I-1502J0D01*
G03X13926Y191501I123J-158D01*
G01Y191185D01*
G03X14003Y191028I200J1D01*
G02X14582Y189843I-923J-1185D01*
G02X11578I-1502J0D01*
G02X12157Y191028I1502J0D01*
G03X12234Y191185I-123J158D01*
G37*
G36*
G01X186118Y197885D02*
Y198201D01*
G03X186041Y198358I-200J-1D01*
G02X185462Y199543I923J1185D01*
G02X188466I1502J0D01*
G02X187887Y198358I-1502J0D01*
G03X187810Y198201I123J-158D01*
G01Y197885D01*
G03X187887Y197728I200J1D01*
G02X188466Y196543I-923J-1185D01*
G02X185462I-1502J0D01*
G02X186041Y197728I1502J0D01*
G03X186118Y197885I-123J158D01*
G37*
G36*
G01X12734Y199985D02*
Y200301D01*
G03X12657Y200458I-200J-1D01*
G02X12078Y201643I923J1185D01*
G02X15082I1502J0D01*
G02X14503Y200458I-1502J0D01*
G03X14426Y200301I123J-158D01*
G01Y199985D01*
G03X14503Y199828I200J1D01*
G02X15082Y198643I-923J-1185D01*
G02X12078I-1502J0D01*
G02X12657Y199828I1502J0D01*
G03X12734Y199985I-123J158D01*
G37*
G36*
G01X32716Y196218D02*
G02X30978Y199243I1764J3025D01*
G02X31278Y200662I3502J1D01*
G03Y200824I-182J81D01*
G02X30978Y202243I3202J1418D01*
G02X37982I3502J0D01*
G02X37682Y200824I-3502J-1D01*
G03Y200662I182J-81D01*
G02X37982Y199243I-3202J-1418D01*
G02X36302Y196252I-3503J0D01*
G01X36256Y196224D01*
X36205Y196133D01*
X36210Y195682D01*
X36262Y195592D01*
X36308Y195565D01*
G02X38046Y192540I-1764J-3025D01*
G02X37746Y191121I-3502J-1D01*
G03Y190959I182J-81D01*
G02X38046Y189540I-3202J-1418D01*
G02X36107Y186406I-3502J0D01*
G01X36056Y186381D01*
X35998Y186288D01*
X35986Y185822D01*
X36041Y185727D01*
X36090Y185699D01*
G02X37882Y182643I-1710J-3056D01*
G02X37582Y181224I-3502J-1D01*
G03Y181062I182J-81D01*
G02X37882Y179643I-3202J-1418D01*
G02X30878I-3502J0D01*
G02X31178Y181062I3502J1D01*
G03Y181224I-182J81D01*
G02X30878Y182643I3202J1418D01*
G02X32817Y185777I3502J0D01*
G01X32868Y185802D01*
X32926Y185895D01*
X32938Y186361D01*
X32883Y186456D01*
X32834Y186484D01*
G02X31042Y189540I1710J3056D01*
G02X31342Y190959I3502J1D01*
G03Y191121I-182J81D01*
G02X31042Y192540I3202J1418D01*
G02X32722Y195531I3503J0D01*
G01X32768Y195559D01*
X32819Y195650D01*
X32814Y196101D01*
X32762Y196191D01*
X32716Y196218D01*
G37*
G36*
G01X185918Y207085D02*
Y207401D01*
G03X185841Y207558I-200J-1D01*
G02X185262Y208743I923J1185D01*
G02X188266I1502J0D01*
G02X187687Y207558I-1502J0D01*
G03X187610Y207401I123J-158D01*
G01Y207085D01*
G03X187687Y206928I200J1D01*
G02X188266Y205743I-923J-1185D01*
G02X185262I-1502J0D01*
G02X185841Y206928I1502J0D01*
G03X185918Y207085I-123J158D01*
G37*
G36*
G01X13945Y208370D02*
Y208686D01*
G03X13868Y208843I-200J-1D01*
G02X13289Y210028I923J1185D01*
G02X16293I1502J0D01*
G02X15714Y208843I-1502J0D01*
G03X15637Y208686I123J-158D01*
G01Y208370D01*
G03X15714Y208213I200J1D01*
G02X16293Y207028I-923J-1185D01*
G02X13289I-1502J0D01*
G02X13868Y208213I1502J0D01*
G03X13945Y208370I-123J158D01*
G37*
G36*
G01X32393Y208847D02*
G02X32693Y207428I-3202J-1418D01*
G02X25689I-3502J0D01*
G02X25989Y208847I3502J1D01*
G03Y209009I-182J81D01*
G02X25689Y210428I3202J1418D01*
G02X32693I3502J0D01*
G02X32393Y209009I-3502J-1D01*
G03Y208847I182J-81D01*
G37*
G36*
G01X182736Y215570D02*
Y215886D01*
G03X182659Y216043I-200J-1D01*
G02X182080Y217228I923J1185D01*
G02X185084I1502J0D01*
G02X184505Y216043I-1502J0D01*
G03X184428Y215886I123J-158D01*
G01Y215570D01*
G03X184505Y215413I200J1D01*
G02X185084Y214228I-923J-1185D01*
G02X182080I-1502J0D01*
G02X182659Y215413I1502J0D01*
G03X182736Y215570I-123J158D01*
G37*
G36*
G01X176156Y228909D02*
G02X175856Y230328I3202J1418D01*
G02X179358Y233830I3502J0D01*
G02X180777Y233530I1J-3502D01*
G03X180939I81J182D01*
G02X182358Y233830I1418J-3202D01*
G02X183777Y233530I1J-3502D01*
G03X183939I81J182D01*
G02X185358Y233830I1418J-3202D01*
G02X188860Y230328I0J-3502D01*
G02X188560Y228909I-3502J-1D01*
G03Y228747I182J-81D01*
G02X188860Y227328I-3202J-1418D01*
G02X185358Y223826I-3502J0D01*
G02X183939Y224126I-1J3502D01*
G03X183777I-81J-182D01*
G02X182358Y223826I-1418J3202D01*
G02X180939Y224126I-1J3502D01*
G03X180777I-81J-182D01*
G02X179358Y223826I-1418J3202D01*
G02X175856Y227328I0J3502D01*
G02X176156Y228747I3502J1D01*
G03Y228909I-182J81D01*
G37*
G36*
G01X164361Y233882D02*
G02X165562Y234095I1203J-3289D01*
G02Y227091I0J-3502D01*
G02X164361Y227304I2J3502D01*
G03X164223I-69J-188D01*
G02X163022Y227091I-1203J3289D01*
G02Y234095I0J3502D01*
G02X164223Y233882I-2J-3502D01*
G03X164361I69J188D01*
G37*
G36*
G01X44978Y233312D02*
G02X44975Y233457I3499J145D01*
G02X48477Y236959I3502J0D01*
G02X49896Y236659I1J-3502D01*
G03X50058I81J182D01*
G02X51477Y236959I1418J-3202D01*
G02X52896Y236659I1J-3502D01*
G03X53058I81J182D01*
G02X54477Y236959I1418J-3202D01*
G02X57979Y233457I0J-3502D01*
G02X57615Y231903I-3502J1D01*
G03X57614Y231728I179J-89D01*
G02X57958Y230214I-3158J-1514D01*
G02X54456Y226712I-3502J0D01*
G02X53037Y227012I-1J3502D01*
G03X52875I-81J-182D01*
G02X51456Y226712I-1418J3202D01*
G02X50037Y227012I-1J3502D01*
G03X49875I-81J-182D01*
G02X48456Y226712I-1418J3202D01*
G02X45629Y228147I0J3502D01*
G01X45601Y228186D01*
X45516Y228229D01*
X45098Y228230D01*
X45013Y228187D01*
X44985Y228148D01*
G02X42167Y226726I-2818J2081D01*
G02X40748Y227026I-1J3502D01*
G03X40586I-81J-182D01*
G02X39167Y226726I-1418J3202D01*
G02Y233730I0J3502D01*
G02X40586Y233430I1J-3502D01*
G03X40748I81J182D01*
G02X42167Y233730I1418J-3202D01*
G02X44331Y232981I0J-3501D01*
G01X44378Y232945D01*
X44493Y232934D01*
X44922Y233153D01*
X44980Y233253D01*
X44978Y233312D01*
G37*
G36*
G01X40825Y243882D02*
X40509D01*
G03X40352Y243805I1J-200D01*
G02X39167Y243226I-1185J923D01*
G02Y246230I0J1502D01*
G02X40352Y245651I0J-1502D01*
G03X40509Y245574I158J123D01*
G01X40825D01*
G03X40982Y245651I-1J200D01*
G02X42167Y246230I1185J-923D01*
G02Y243226I0J-1502D01*
G02X40982Y243805I0J1502D01*
G03X40825Y243882I-158J-123D01*
G37*
G36*
G01X164516D02*
X164200D01*
G03X164043Y243805I1J-200D01*
G02X162858Y243226I-1185J923D01*
G02Y246230I0J1502D01*
G02X164043Y245651I0J-1502D01*
G03X164200Y245574I158J123D01*
G01X164516D01*
G03X164673Y245651I-1J200D01*
G02X165858Y246230I1185J-923D01*
G02Y243226I0J-1502D01*
G02X164673Y243805I0J1502D01*
G03X164516Y243882I-158J-123D01*
G37*
G36*
G01X181077Y240326D02*
G02X179658Y240026I-1418J3202D01*
G02Y247030I0J3502D01*
G02X181077Y246730I1J-3502D01*
G03X181239I81J182D01*
G02X182658Y247030I1418J-3202D01*
G02X184077Y246730I1J-3502D01*
G03X184239I81J182D01*
G02X185658Y247030I1418J-3202D01*
G02Y240026I0J-3502D01*
G02X184239Y240326I-1J3502D01*
G03X184077I-81J-182D01*
G02X182658Y240026I-1418J3202D01*
G02X181239Y240326I-1J3502D01*
G03X181077I-81J-182D01*
G37*
G36*
G01X52386Y243026D02*
G02X50967Y242726I-1418J3202D01*
G02Y249730I0J3502D01*
G02X52386Y249430I1J-3502D01*
G03X52548I81J182D01*
G02X53967Y249730I1418J-3202D01*
G02X55386Y249430I1J-3502D01*
G03X55548I81J182D01*
G02X56967Y249730I1418J-3202D01*
G02Y242726I0J-3502D01*
G02X55548Y243026I-1J3502D01*
G03X55386I-81J-182D01*
G02X53967Y242726I-1418J3202D01*
G02X52548Y243026I-1J3502D01*
G03X52386I-81J-182D01*
G37*
G36*
G01X182409Y257374D02*
X182725D01*
G03X182882Y257451I-1J200D01*
G02X185252I1185J-923D01*
G03X185409Y257374I158J123D01*
G01X185725D01*
G03X185882Y257451I-1J200D01*
G02X187067Y258030I1185J-923D01*
G02X188569Y256528I0J-1502D01*
G02X188043Y255386I-1503J0D01*
G01X188010Y255358D01*
X187974Y255284D01*
X187961Y254904D01*
X187991Y254827D01*
X188022Y254797D01*
G02X188469Y253728I-1055J-1069D01*
G02X186967Y252226I-1502J0D01*
G02X185782Y252805I0J1502D01*
G03X185625Y252882I-158J-123D01*
G01X185309D01*
G03X185152Y252805I1J-200D01*
G02X182782I-1185J923D01*
G03X182625Y252882I-158J-123D01*
G01X182309D01*
G03X182152Y252805I1J-200D01*
G02X179782I-1185J923D01*
G03X179625Y252882I-158J-123D01*
G01X179309D01*
G03X179152Y252805I1J-200D01*
G02X177967Y252226I-1185J923D01*
G02X176465Y253728I0J1502D01*
G02X176991Y254870I1503J0D01*
G01X177024Y254898D01*
X177060Y254972D01*
X177073Y255352D01*
X177043Y255429D01*
X177012Y255459D01*
G02X176565Y256528I1055J1069D01*
G02X178067Y258030I1502J0D01*
G02X179252Y257451I0J-1502D01*
G03X179409Y257374I158J123D01*
G01X179725D01*
G03X179882Y257451I-1J200D01*
G02X182252I1185J-923D01*
G03X182409Y257374I158J123D01*
G37*
G36*
G01X56509Y260074D02*
X56825D01*
G03X56982Y260151I-1J200D01*
G02X59352I1185J-923D01*
G03X59509Y260074I158J123D01*
G01X59825D01*
G03X59982Y260151I-1J200D01*
G02X61167Y260730I1185J-923D01*
G02X62669Y259228I0J-1502D01*
G02X62139Y258083I-1502J0D01*
G03X62068Y257930I129J-153D01*
G01Y257626D01*
G03X62139Y257473I200J0D01*
G02X62669Y256328I-972J-1145D01*
G02X61167Y254826I-1502J0D01*
G02X59982Y255405I0J1502D01*
G03X59825Y255482I-158J-123D01*
G01X59509D01*
G03X59352Y255405I1J-200D01*
G02X56982I-1185J923D01*
G03X56825Y255482I-158J-123D01*
G01X56509D01*
G03X56352Y255405I1J-200D01*
G02X53982I-1185J923D01*
G03X53825Y255482I-158J-123D01*
G01X53509D01*
G03X53352Y255405I1J-200D01*
G02X52167Y254826I-1185J923D01*
G02X50665Y256328I0J1502D01*
G02X51195Y257473I1502J0D01*
G03X51266Y257626I-129J153D01*
G01Y257930D01*
G03X51195Y258083I-200J0D01*
G02X50665Y259228I972J1145D01*
G02X52167Y260730I1502J0D01*
G02X53352Y260151I0J-1502D01*
G03X53509Y260074I158J123D01*
G01X53825D01*
G03X53982Y260151I-1J200D01*
G02X56352I1185J-923D01*
G03X56509Y260074I158J123D01*
G37*
G36*
G01X182600Y270374D02*
X182916D01*
G03X183073Y270451I-1J200D01*
G02X185443I1185J-923D01*
G03X185600Y270374I158J123D01*
G01X185916D01*
G03X186073Y270451I-1J200D01*
G02X187258Y271030I1185J-923D01*
G02Y268026I0J-1502D01*
G02X186073Y268605I0J1502D01*
G03X185916Y268682I-158J-123D01*
G01X185600D01*
G03X185443Y268605I1J-200D01*
G02X183073I-1185J923D01*
G03X182916Y268682I-158J-123D01*
G01X182600D01*
G03X182443Y268605I1J-200D01*
G02X180073I-1185J923D01*
G03X179916Y268682I-158J-123D01*
G01X179600D01*
G03X179443Y268605I1J-200D01*
G02X178258Y268026I-1185J923D01*
G02Y271030I0J1502D01*
G02X179443Y270451I0J-1502D01*
G03X179600Y270374I158J123D01*
G01X179916D01*
G03X180073Y270451I-1J200D01*
G02X182443I1185J-923D01*
G03X182600Y270374I158J123D01*
G37*
G36*
G01X22527Y290074D02*
X22843D01*
G03X23000Y290151I-1J200D01*
G02X25370I1185J-923D01*
G03X25527Y290074I158J123D01*
G01X25843D01*
G03X26000Y290151I-1J200D01*
G02X27185Y290730I1185J-923D01*
G02X28687Y289228I0J-1502D01*
G02X28108Y288043I-1502J0D01*
G03X28031Y287886I123J-158D01*
G01Y287570D01*
G03X28108Y287413I200J1D01*
G02X28687Y286228I-923J-1185D01*
G02X27185Y284726I-1502J0D01*
G02X26000Y285305I0J1502D01*
G03X25843Y285382I-158J-123D01*
G01X25527D01*
G03X25370Y285305I1J-200D01*
G02X23000I-1185J923D01*
G03X22843Y285382I-158J-123D01*
G01X22527D01*
G03X22370Y285305I1J-200D01*
G02X20000I-1185J923D01*
G03X19843Y285382I-158J-123D01*
G01X19527D01*
G03X19370Y285305I1J-200D01*
G02X18185Y284726I-1185J923D01*
G02X16683Y286228I0J1502D01*
G02X17262Y287413I1502J0D01*
G03X17339Y287570I-123J158D01*
G01Y287886D01*
G03X17262Y288043I-200J-1D01*
G02X16683Y289228I923J1185D01*
G02X18185Y290730I1502J0D01*
G02X19370Y290151I0J-1502D01*
G03X19527Y290074I158J123D01*
G01X19843D01*
G03X20000Y290151I-1J200D01*
G02X22370I1185J-923D01*
G03X22527Y290074I158J123D01*
G37*
G36*
G01X131824D02*
X132140D01*
G03X132297Y290151I-1J200D01*
G02X134667I1185J-923D01*
G03X134824Y290074I158J123D01*
G01X135140D01*
G03X135297Y290151I-1J200D01*
G02X136482Y290730I1185J-923D01*
G02X137984Y289228I0J-1502D01*
G02X137405Y288043I-1502J0D01*
G03X137328Y287886I123J-158D01*
G01Y287570D01*
G03X137405Y287413I200J1D01*
G02X137984Y286228I-923J-1185D01*
G02X136482Y284726I-1502J0D01*
G02X135297Y285305I0J1502D01*
G03X135140Y285382I-158J-123D01*
G01X134824D01*
G03X134667Y285305I1J-200D01*
G02X132297I-1185J923D01*
G03X132140Y285382I-158J-123D01*
G01X131824D01*
G03X131667Y285305I1J-200D01*
G02X129297I-1185J923D01*
G03X129140Y285382I-158J-123D01*
G01X128824D01*
G03X128667Y285305I1J-200D01*
G02X127482Y284726I-1185J923D01*
G02X125980Y286228I0J1502D01*
G02X126559Y287413I1502J0D01*
G03X126636Y287570I-123J158D01*
G01Y287886D01*
G03X126559Y288043I-200J-1D01*
G02X125980Y289228I923J1185D01*
G02X127482Y290730I1502J0D01*
G02X128667Y290151I0J-1502D01*
G03X128824Y290074I158J123D01*
G01X129140D01*
G03X129297Y290151I-1J200D01*
G02X131667I1185J-923D01*
G03X131824Y290074I158J123D01*
G37*
G36*
G01X38843Y300882D02*
X38527D01*
G03X38370Y300805I1J-200D01*
G02X37185Y300226I-1185J923D01*
G02Y303230I0J1502D01*
G02X38370Y302651I0J-1502D01*
G03X38527Y302574I158J123D01*
G01X38843D01*
G03X39000Y302651I-1J200D01*
G02X40185Y303230I1185J-923D01*
G02Y300226I0J-1502D01*
G02X39000Y300805I0J1502D01*
G03X38843Y300882I-158J-123D01*
G37*
G36*
G01X148140D02*
X147824D01*
G03X147667Y300805I1J-200D01*
G02X146482Y300226I-1185J923D01*
G02Y303230I0J1502D01*
G02X147667Y302651I0J-1502D01*
G03X147824Y302574I158J123D01*
G01X148140D01*
G03X148297Y302651I-1J200D01*
G02X149482Y303230I1185J-923D01*
G02Y300226I0J-1502D01*
G02X148297Y300805I0J1502D01*
G03X148140Y300882I-158J-123D01*
G37*
G36*
G01X19766Y318430D02*
G02X21185Y318730I1418J-3202D01*
G02X22604Y318430I1J-3502D01*
G03X22766I81J182D01*
G02X24185Y318730I1418J-3202D01*
G02X25604Y318430I1J-3502D01*
G03X25766I81J182D01*
G02X27185Y318730I1418J-3202D01*
G02X30687Y315228I0J-3502D01*
G02X30387Y313809I-3502J-1D01*
G03Y313647I182J-81D01*
G02X30687Y312228I-3202J-1418D01*
G02X27185Y308726I-3502J0D01*
G02X25766Y309026I-1J3502D01*
G03X25604I-81J-182D01*
G02X24185Y308726I-1418J3202D01*
G02X22766Y309026I-1J3502D01*
G03X22604I-81J-182D01*
G02X21185Y308726I-1418J3202D01*
G02X19766Y309026I-1J3502D01*
G03X19604I-81J-182D01*
G02X18185Y308726I-1418J3202D01*
G02X14683Y312228I0J3502D01*
G02X14983Y313647I3502J1D01*
G03Y313809I-182J81D01*
G02X14683Y315228I3202J1418D01*
G02X18185Y318730I3502J0D01*
G02X19604Y318430I1J-3502D01*
G03X19766I81J182D01*
G37*
G36*
G01X38766Y319430D02*
G02X40185Y319730I1418J-3202D01*
G02Y312726I0J-3502D01*
G02X38766Y313026I-1J3502D01*
G03X38604I-81J-182D01*
G02X37185Y312726I-1418J3202D01*
G02Y319730I0J3502D01*
G02X38604Y319430I1J-3502D01*
G03X38766I81J182D01*
G37*
G36*
G01X148063D02*
G02X149482Y319730I1418J-3202D01*
G02Y312726I0J-3502D01*
G02X148063Y313026I-1J3502D01*
G03X147901I-81J-182D01*
G02X146482Y312726I-1418J3202D01*
G02Y319730I0J3502D01*
G02X147901Y319430I1J-3502D01*
G03X148063I81J182D01*
G37*
G36*
G01X162060Y330647D02*
G02X162360Y329228I-3202J-1418D01*
G02X155356I-3502J0D01*
G02X155656Y330647I3502J1D01*
G03Y330809I-182J81D01*
G02X155356Y332228I3202J1418D01*
G02X162360I3502J0D01*
G02X162060Y330809I-3502J-1D01*
G03Y330647I182J-81D01*
G37*
G36*
G01X181800Y336674D02*
X182116D01*
G03X182273Y336751I-1J200D01*
G02X184643I1185J-923D01*
G03X184800Y336674I158J123D01*
G01X185116D01*
G03X185273Y336751I-1J200D01*
G02X186458Y337330I1185J-923D01*
G02Y334326I0J-1502D01*
G02X185273Y334905I0J1502D01*
G03X185116Y334982I-158J-123D01*
G01X184800D01*
G03X184643Y334905I1J-200D01*
G02X182273I-1185J923D01*
G03X182116Y334982I-158J-123D01*
G01X181800D01*
G03X181643Y334905I1J-200D01*
G02X179273I-1185J923D01*
G03X179116Y334982I-158J-123D01*
G01X178800D01*
G03X178643Y334905I1J-200D01*
G02X177458Y334326I-1185J923D01*
G02Y337330I0J1502D01*
G02X178643Y336751I0J-1502D01*
G03X178800Y336674I158J123D01*
G01X179116D01*
G03X179273Y336751I-1J200D01*
G02X181643I1185J-923D01*
G03X181800Y336674I158J123D01*
G37*
G36*
G01X129117Y338482D02*
Y338818D01*
X129092Y338885D01*
X129068Y338913D01*
G02X128698Y339900I1131J987D01*
G02X131702I1502J0D01*
G02X131332Y338913I-1501J0D01*
G01X131308Y338885D01*
X131283Y338818D01*
Y338482D01*
X131308Y338415D01*
X131332Y338387D01*
G02X131702Y337400I-1131J-987D01*
G02X128698I-1502J0D01*
G02X129068Y338387I1501J0D01*
G01X129092Y338415D01*
X129117Y338482D01*
G37*
G36*
G01X147856Y338390D02*
G02X148102Y337100I-3256J-1289D01*
G02X141098I-3502J0D01*
G02X141344Y338390I3502J1D01*
G03Y338538I-186J74D01*
G02X141098Y339828I3256J1289D01*
G02X148102I3502J0D01*
G02X147856Y338538I-3502J-1D01*
G03Y338390I186J-74D01*
G37*
G36*
G01X49704Y347315D02*
G02X49498Y348497I3296J1183D01*
G02X49704Y349679I3502J-1D01*
G03Y349815I-189J68D01*
G02X49498Y350997I3296J1183D01*
G02X56502I3502J0D01*
G02X56296Y349815I-3502J1D01*
G03Y349679I189J-68D01*
G02X56502Y348497I-3296J-1183D01*
G02X56296Y347315I-3502J1D01*
G03Y347179I189J-68D01*
G02X56501Y346060I-3296J-1182D01*
G03X56647Y345871I200J4D01*
G02X59202Y342500I-946J-3371D01*
G02X55700Y338998I-3502J0D01*
G02X52199Y342437I0J3502D01*
G03X52053Y342626I-200J-4D01*
G02X49498Y345997I946J3371D01*
G02X49704Y347179I3502J-1D01*
G03Y347315I-189J68D01*
G37*
G36*
G01X146644Y347738D02*
G02X146398Y349028I3256J1289D01*
G02X146653Y350339I3502J-1D01*
G03Y350489I-186J75D01*
G02X146398Y351800I3247J1312D01*
G02X153402I3502J0D01*
G02X153147Y350489I-3502J1D01*
G03Y350339I186J-75D01*
G02X153402Y349028I-3247J-1312D01*
G02X153156Y347738I-3502J-1D01*
G03Y347590I186J-74D01*
G02X153402Y346300I-3256J-1289D01*
G02X146398I-3502J0D01*
G02X146644Y347590I3502J1D01*
G03Y347738I-186J74D01*
G37*
G36*
G01X19081Y364930D02*
G02X20500Y365230I1418J-3202D01*
G02X21919Y364930I1J-3502D01*
G03X22081I81J182D01*
G02X23500Y365230I1418J-3202D01*
G02X24919Y364930I1J-3502D01*
G03X25081I81J182D01*
G02X26500Y365230I1418J-3202D01*
G02X30002Y361728I0J-3502D01*
G02X29702Y360309I-3502J-1D01*
G03Y360147I182J-81D01*
G02X30002Y358728I-3202J-1418D01*
G02X26500Y355226I-3502J0D01*
G02X25081Y355526I-1J3502D01*
G03X24919I-81J-182D01*
G02X23500Y355226I-1418J3202D01*
G02X22081Y355526I-1J3502D01*
G03X21919I-81J-182D01*
G02X20500Y355226I-1418J3202D01*
G02X19081Y355526I-1J3502D01*
G03X18919I-81J-182D01*
G02X17500Y355226I-1418J3202D01*
G02X13998Y358728I0J3502D01*
G02X14298Y360147I3502J1D01*
G03Y360309I-182J81D01*
G02X13998Y361728I3202J1418D01*
G02X17500Y365230I3502J0D01*
G02X18919Y364930I1J-3502D01*
G03X19081I81J182D01*
G37*
G36*
G01X178439Y365492D02*
G02X179858Y365792I1418J-3202D01*
G02X181277Y365492I1J-3502D01*
G03X181439I81J182D01*
G02X182858Y365792I1418J-3202D01*
G02X184277Y365492I1J-3502D01*
G03X184439I81J182D01*
G02X185858Y365792I1418J-3202D01*
G02X189360Y362290I0J-3502D01*
G02X189154Y361108I-3502J1D01*
G03Y360972I189J-68D01*
G02X189360Y359790I-3296J-1183D01*
G02X185858Y356288I-3502J0D01*
G02X184439Y356588I-1J3502D01*
G03X184277I-81J-182D01*
G02X182858Y356288I-1418J3202D01*
G02X181439Y356588I-1J3502D01*
G03X181277I-81J-182D01*
G02X179858Y356288I-1418J3202D01*
G02X178439Y356588I-1J3502D01*
G03X178277I-81J-182D01*
G02X176858Y356288I-1418J3202D01*
G02X173356Y359790I0J3502D01*
G02X173562Y360972I3502J-1D01*
G03Y361108I-189J68D01*
G02X173356Y362290I3296J1183D01*
G02X176858Y365792I3502J0D01*
G02X178277Y365492I1J-3502D01*
G03X178439I81J182D01*
G37*
G36*
G01X73345Y369082D02*
Y369418D01*
X73320Y369485D01*
X73296Y369513D01*
G02X72926Y370500I1131J987D01*
G02X75930I1502J0D01*
G02X75560Y369513I-1501J0D01*
G01X75536Y369485D01*
X75511Y369418D01*
Y369082D01*
X75536Y369015D01*
X75560Y368987D01*
G02Y367013I-1131J-987D01*
G01X75536Y366985D01*
X75511Y366918D01*
Y366582D01*
X75536Y366515D01*
X75560Y366487D01*
G02X75930Y365500I-1131J-987D01*
G02X72926I-1502J0D01*
G02X73296Y366487I1501J0D01*
G01X73320Y366515D01*
X73345Y366582D01*
Y366918D01*
X73320Y366985D01*
X73296Y367013D01*
G02Y368987I1131J987D01*
G01X73320Y369015D01*
X73345Y369082D01*
G37*
G36*
G01X49704Y366315D02*
G02X49498Y367497I3296J1183D01*
G02X49704Y368679I3502J-1D01*
G03Y368815I-189J68D01*
G02X49498Y369997I3296J1183D01*
G02X56502I3502J0D01*
G02X56296Y368815I-3502J1D01*
G03Y368679I189J-68D01*
G02X56502Y367497I-3296J-1183D01*
G02X56296Y366315I-3502J1D01*
G03Y366179I189J-68D01*
G02X56502Y364997I-3296J-1183D01*
G02X49498I-3502J0D01*
G02X49704Y366179I3502J-1D01*
G03Y366315I-189J68D01*
G37*
G36*
G01X146748Y366001D02*
G02X146398Y367528I3152J1526D01*
G02X146653Y368839I3502J-1D01*
G03Y368989I-186J75D01*
G02X146398Y370300I3247J1312D01*
G02X153402I3502J0D01*
G02X153147Y368989I-3502J1D01*
G03Y368839I186J-75D01*
G02X153402Y367528I-3247J-1312D01*
G02X153052Y366001I-3502J-1D01*
G03Y365827I180J-87D01*
G02X153402Y364300I-3152J-1526D01*
G02X146398I-3502J0D01*
G02X146748Y365827I3502J1D01*
G03Y366001I-180J87D01*
G37*
G36*
G01X24347Y432837D02*
X24406Y433276D01*
X24369Y433372D01*
X24329Y433405D01*
G02X23176Y435866I2050J2461D01*
G02X29580I3202J0D01*
G02X28427Y433405I-3203J0D01*
G01X28387Y433372D01*
X28350Y433276D01*
X28409Y432837D01*
X28471Y432755D01*
X28518Y432733D01*
G02X31119Y430132I-2140J-4741D01*
G01X31141Y430085D01*
X31223Y430023D01*
X31662Y429964D01*
X31758Y430001D01*
X31791Y430041D01*
G02X34252Y431194I2461J-2050D01*
G02Y424790I0J-3202D01*
G02X31791Y425943I0J3203D01*
G01X31758Y425983D01*
X31662Y426020D01*
X31223Y425961D01*
X31141Y425899D01*
X31119Y425852D01*
G02X28518Y423251I-4741J2140D01*
G01X28471Y423229D01*
X28409Y423147D01*
X28350Y422708D01*
X28387Y422612D01*
X28427Y422579D01*
G02X29580Y420118I-2050J-2461D01*
G02X23176I-3202J0D01*
G02X24329Y422579I3203J0D01*
G01X24369Y422612D01*
X24406Y422708D01*
X24347Y423147D01*
X24285Y423229D01*
X24238Y423251D01*
G02Y432733I2139J4741D01*
G01X24285Y432755D01*
X24347Y432837D01*
G37*
G36*
G01Y456459D02*
X24406Y456898D01*
X24369Y456994D01*
X24329Y457027D01*
G02X23176Y459488I2050J2461D01*
G02X29580I3202J0D01*
G02X28427Y457027I-3203J0D01*
G01X28387Y456994D01*
X28350Y456898D01*
X28409Y456459D01*
X28471Y456377D01*
X28518Y456355D01*
G02X31119Y453754I-2140J-4741D01*
G01X31141Y453707D01*
X31223Y453645D01*
X31662Y453586D01*
X31758Y453623D01*
X31791Y453663D01*
G02X34252Y454816I2461J-2050D01*
G02X37454Y451614I0J-3202D01*
G02X36301Y449153I-3203J0D01*
G01X36261Y449120D01*
X36224Y449024D01*
X36283Y448585D01*
X36345Y448503D01*
X36392Y448481D01*
G02Y438999I-2139J-4741D01*
G01X36345Y438977D01*
X36283Y438895D01*
X36224Y438456D01*
X36261Y438360D01*
X36301Y438327D01*
G02X37454Y435866I-2050J-2461D01*
G02X31050I-3202J0D01*
G02X32203Y438327I3203J0D01*
G01X32243Y438360D01*
X32280Y438456D01*
X32221Y438895D01*
X32159Y438977D01*
X32112Y438999D01*
G02X29511Y441600I2140J4741D01*
G01X29489Y441647D01*
X29407Y441709D01*
X28968Y441768D01*
X28872Y441731D01*
X28839Y441691D01*
G02X26378Y440538I-2461J2050D01*
G02X23176Y443740I0J3202D01*
G02X24329Y446201I3203J0D01*
G01X24369Y446234D01*
X24406Y446330D01*
X24347Y446769D01*
X24285Y446851D01*
X24238Y446873D01*
G02Y456355I2139J4741D01*
G01X24285Y456377D01*
X24347Y456459D01*
G37*
G36*
G01X19417Y496082D02*
Y496418D01*
X19392Y496485D01*
X19368Y496513D01*
G02X18998Y497500I1131J987D01*
G02X22002I1502J0D01*
G02X21632Y496513I-1501J0D01*
G01X21608Y496485D01*
X21583Y496418D01*
Y496082D01*
X21608Y496015D01*
X21632Y495987D01*
G02X22002Y495000I-1131J-987D01*
G02X18998I-1502J0D01*
G02X19368Y495987I1501J0D01*
G01X19392Y496015D01*
X19417Y496082D01*
G37*
G36*
G01X31789Y46811D02*
X31749Y46861D01*
G02X31050Y48858I2503J1997D01*
G02X34252Y45656I3202J0D01*
G02X34023Y45664I-3J3202D01*
G01X33959Y45669D01*
X33851Y45604D01*
X33648Y45142D01*
X33673Y45019D01*
X33719Y44975D01*
G02X26911I-3404J-3597D01*
G01X26957Y45019D01*
X26982Y45142D01*
X26779Y45604D01*
X26671Y45669D01*
X26607Y45664D01*
G02X26378Y45656I-226J3194D01*
G02X29580Y48858I0J3202D01*
G02X28881Y46861I-3202J0D01*
G01X28841Y46811D01*
X28833Y46685D01*
X29099Y46256D01*
X29215Y46207D01*
X29277Y46220D01*
G02X31353I1038J-4842D01*
G01X31415Y46207D01*
X31531Y46256D01*
X31797Y46685D01*
X31789Y46811D01*
G37*
G36*
G01X169870Y107815D02*
X169824Y107859D01*
G02X176632I3404J3597D01*
G01X176586Y107815D01*
X176561Y107692D01*
X176764Y107230D01*
X176872Y107165D01*
X176936Y107170D01*
G02X177165Y107178I226J-3194D01*
G02X173963Y103976I0J-3202D01*
G02X174662Y105973I3202J0D01*
G01X174702Y106023D01*
X174710Y106149D01*
X174444Y106578D01*
X174328Y106627D01*
X174266Y106614D01*
G02X172190I-1038J4842D01*
G01X172128Y106627D01*
X172012Y106578D01*
X171746Y106149D01*
X171754Y106023D01*
X171794Y105973D01*
G02X172493Y103976I-2503J-1997D01*
G02X169291Y107178I-3202J0D01*
G02X169520Y107170I3J-3202D01*
G01X169584Y107165D01*
X169692Y107230D01*
X169895Y107692D01*
X169870Y107815D01*
G37*
G36*
G01X165362Y216124D02*
G02X165062Y217543I3202J1418D01*
G02X172066I3502J0D01*
G02X171766Y216124I-3502J-1D01*
G03Y215962I182J-81D01*
G02X172066Y214543I-3202J-1418D01*
G02X168564Y211041I-3502J0D01*
G02X168117Y211070I3J3502D01*
G01X168057Y211077D01*
X167952Y211026D01*
X167700Y210611D01*
X167703Y210494D01*
X167738Y210444D01*
G02X168366Y208443I-2874J-2001D01*
G02X168066Y207024I-3502J-1D01*
G03Y206862I182J-81D01*
G02X168366Y205443I-3202J-1418D01*
G02X167200Y202834I-3502J0D01*
G01X167167Y202805D01*
X167133Y202726D01*
X167140Y202335D01*
X167176Y202258D01*
X167211Y202229D01*
G02X168466Y199543I-2247J-2686D01*
G02X168166Y198124I-3502J-1D01*
G03Y197962I182J-81D01*
G02X168466Y196543I-3202J-1418D01*
G02X166162Y193252I-3502J0D01*
G01X166101Y193230D01*
X166029Y193124D01*
X166042Y192615D01*
X166120Y192513D01*
X166182Y192494D01*
G02X168666Y189143I-1018J-3351D01*
G02X168366Y187724I-3502J-1D01*
G03Y187562I182J-81D01*
G02X168666Y186143I-3202J-1418D01*
G02X161662I-3502J0D01*
G02X161962Y187562I3502J1D01*
G03Y187724I-182J81D01*
G02X161662Y189143I3202J1418D01*
G02X163966Y192434I3502J0D01*
G01X164027Y192456D01*
X164099Y192562D01*
X164086Y193071D01*
X164008Y193173D01*
X163946Y193192D01*
G02X161462Y196543I1018J3351D01*
G02X161762Y197962I3502J1D01*
G03Y198124I-182J81D01*
G02X161462Y199543I3202J1418D01*
G02X162628Y202152I3502J0D01*
G01X162661Y202181D01*
X162695Y202260D01*
X162688Y202651D01*
X162652Y202728D01*
X162617Y202757D01*
G02X161362Y205443I2247J2686D01*
G02X161662Y206862I3502J1D01*
G03Y207024I-182J81D01*
G02X161362Y208443I3202J1418D01*
G02X164864Y211945I3502J0D01*
G02X165311Y211916I-3J-3502D01*
G01X165371Y211909D01*
X165476Y211960D01*
X165728Y212375D01*
X165725Y212492D01*
X165690Y212542D01*
G02X165062Y214543I2874J2001D01*
G02X165362Y215962I3502J1D01*
G03Y216124I-182J81D01*
G37*
G36*
G01X28109Y238389D02*
G02X29291Y238595I1183J-3296D01*
G02X30511Y238376I1J-3502D01*
G03X30651I70J187D01*
G02X31871Y238595I1219J-3283D01*
G02X35373Y235093I0J-3502D01*
G02X35167Y233911I-3502J1D01*
G03Y233775I189J-68D01*
G02X35373Y232593I-3296J-1183D01*
G02X31871Y229091I-3502J0D01*
G02X30670Y229304I2J3502D01*
G03X30532I-69J-188D01*
G02X29331Y229091I-1203J3289D01*
G02X28130Y229304I2J3502D01*
G03X27992I-69J-188D01*
G02X26791Y229091I-1203J3289D01*
G02X23721Y230908I0J3502D01*
G01X23692Y230960D01*
X23587Y231016D01*
X23103Y230972D01*
X23010Y230898D01*
X22991Y230841D01*
G02X22963Y230762I-3314J1130D01*
G03Y230626I189J-68D01*
G02X23169Y229444I-3296J-1183D01*
G02X19667Y225942I-3502J0D01*
G02X18466Y226155I2J3502D01*
G03X18328I-69J-188D01*
G02X17127Y225942I-1203J3289D01*
G02X15926Y226155I2J3502D01*
G03X15788I-69J-188D01*
G02X14587Y225942I-1203J3289D01*
G02X11085Y229444I0J3502D01*
G02X11291Y230626I3502J-1D01*
G03Y230762I-189J68D01*
G02X11085Y231944I3296J1183D01*
G02X14587Y235446I3502J0D01*
G02X15769Y235240I-1J-3502D01*
G03X15905I68J189D01*
G02X17087Y235446I1183J-3296D01*
G02X18307Y235227I1J-3502D01*
G03X18447I70J187D01*
G02X19667Y235446I1219J-3283D01*
G02X22737Y233629I0J-3502D01*
G01X22766Y233577D01*
X22871Y233521D01*
X23355Y233565D01*
X23448Y233639D01*
X23467Y233696D01*
G02X23495Y233775I3314J-1130D01*
G03Y233911I-189J68D01*
G02X23289Y235093I3296J1183D01*
G02X26791Y238595I3502J0D01*
G02X27973Y238389I-1J-3502D01*
G03X28109I68J189D01*
G37*
G36*
G01X16103Y246984D02*
G02X14791Y246213I-1312J731D01*
G02Y249217I0J1502D01*
G02X15841Y248789I0J-1502D01*
G03X16470Y248881I279J286D01*
G02X17782Y249652I1312J-731D01*
G02Y246648I0J-1502D01*
G02X16732Y247076I0J1502D01*
G03X16103Y246984I-279J-286D01*
G37*
G36*
G01X164948Y296370D02*
G02X164296Y296221I-652J1352D01*
G02Y299225I0J1502D01*
G02X165779Y297960I0J-1502D01*
G03X166348Y297663I395J63D01*
G02X167000Y297812I652J-1352D01*
G02Y294808I0J-1502D01*
G02X165517Y296073I0J1502D01*
G03X164948Y296370I-395J-63D01*
G37*
G36*
G01X55929Y298469D02*
G02X55928Y298520I1501J55D01*
G02X57430Y297018I1502J0D01*
G02X56954Y297096I2J1502D01*
G03X56427Y296702I-127J-379D01*
G02X56428Y296651I-1501J-55D01*
G02X54926Y298153I-1502J0D01*
G02X55402Y298075I-2J-1502D01*
G03X55929Y298469I127J379D01*
G37*
G36*
G01X62455Y298221D02*
G02X61420Y297808I-1035J1090D01*
G02Y300812I0J1502D01*
G02X62866Y299717I0J-1502D01*
G03X63526Y299535I385J108D01*
G02X64561Y299948I1035J-1090D01*
G02Y296944I0J-1502D01*
G02X63115Y298039I0J1502D01*
G03X62455Y298221I-385J-108D01*
G37*
G36*
G01X61024Y320301D02*
G02X62225Y320514I1203J-3289D01*
G02X63426Y320301I-2J-3502D01*
G03X63564I69J188D01*
G02X64765Y320514I1203J-3289D01*
G02X68267Y317012I0J-3502D01*
G02X68061Y315830I-3502J1D01*
G03Y315694I189J-68D01*
G02X68267Y314512I-3296J-1183D01*
G02X64765Y311010I-3502J0D01*
G02X63583Y311216I1J3502D01*
G03X63447I-68J-189D01*
G02X62265Y311010I-1183J3296D01*
G02X61045Y311229I-1J3502D01*
G03X60905I-70J-187D01*
G02X59685Y311010I-1219J3283D01*
G02X56615Y312827I0J3502D01*
G01X56586Y312879D01*
X56481Y312935D01*
X55997Y312891D01*
X55904Y312817D01*
X55885Y312760D01*
G02X55857Y312681I-3314J1130D01*
G03Y312545I189J-68D01*
G02X56063Y311363I-3296J-1183D01*
G02X52561Y307861I-3502J0D01*
G02X51379Y308067I1J3502D01*
G03X51243I-68J-189D01*
G02X50061Y307861I-1183J3296D01*
G02X48841Y308080I-1J3502D01*
G03X48701I-70J-187D01*
G02X47481Y307861I-1219J3283D01*
G02X43979Y311363I0J3502D01*
G02X44185Y312545I3502J-1D01*
G03Y312681I-189J68D01*
G02X43979Y313863I3296J1183D01*
G02X47481Y317365I3502J0D01*
G02X48682Y317152I-2J-3502D01*
G03X48820I69J188D01*
G02X50021Y317365I1203J-3289D01*
G02X51222Y317152I-2J-3502D01*
G03X51360I69J188D01*
G02X52561Y317365I1203J-3289D01*
G02X55631Y315548I0J-3502D01*
G01X55660Y315496D01*
X55765Y315440D01*
X56249Y315484D01*
X56342Y315558D01*
X56361Y315615D01*
G02X56389Y315694I3314J-1130D01*
G03Y315830I-189J68D01*
G02X56183Y317012I3296J1183D01*
G02X59685Y320514I3502J0D01*
G02X60886Y320301I-2J-3502D01*
G03X61024I69J188D01*
G37*
G36*
G01X170321D02*
G02X171522Y320514I1203J-3289D01*
G02X172723Y320301I-2J-3502D01*
G03X172861I69J188D01*
G02X174062Y320514I1203J-3289D01*
G02X177564Y317012I0J-3502D01*
G02X177358Y315830I-3502J1D01*
G03Y315694I189J-68D01*
G02X177564Y314512I-3296J-1183D01*
G02X174062Y311010I-3502J0D01*
G02X172880Y311216I1J3502D01*
G03X172744I-68J-189D01*
G02X171562Y311010I-1183J3296D01*
G02X170342Y311229I-1J3502D01*
G03X170202I-70J-187D01*
G02X168982Y311010I-1219J3283D01*
G02X165912Y312827I0J3502D01*
G01X165883Y312879D01*
X165778Y312935D01*
X165294Y312891D01*
X165201Y312817D01*
X165182Y312760D01*
G02X165154Y312681I-3314J1130D01*
G03Y312545I189J-68D01*
G02X165360Y311363I-3296J-1183D01*
G02X161858Y307861I-3502J0D01*
G02X160676Y308067I1J3502D01*
G03X160540I-68J-189D01*
G02X159358Y307861I-1183J3296D01*
G02X158138Y308080I-1J3502D01*
G03X157998I-70J-187D01*
G02X156778Y307861I-1219J3283D01*
G02X153276Y311363I0J3502D01*
G02X153482Y312545I3502J-1D01*
G03Y312681I-189J68D01*
G02X153276Y313863I3296J1183D01*
G02X156778Y317365I3502J0D01*
G02X157979Y317152I-2J-3502D01*
G03X158117I69J188D01*
G02X159318Y317365I1203J-3289D01*
G02X160519Y317152I-2J-3502D01*
G03X160657I69J188D01*
G02X161858Y317365I1203J-3289D01*
G02X164928Y315548I0J-3502D01*
G01X164957Y315496D01*
X165062Y315440D01*
X165546Y315484D01*
X165639Y315558D01*
X165658Y315615D01*
G02X165686Y315694I3314J-1130D01*
G03Y315830I-189J68D01*
G02X165480Y317012I3296J1183D01*
G02X168982Y320514I3502J0D01*
G02X170183Y320301I-2J-3502D01*
G03X170321I69J188D01*
G37*
G36*
G01X31789Y410197D02*
X31749Y410247D01*
G02X31050Y412244I2503J1997D01*
G02X34252Y409042I3202J0D01*
G02X34023Y409050I-3J3202D01*
G01X33959Y409055D01*
X33851Y408990D01*
X33648Y408528D01*
X33673Y408405D01*
X33719Y408361D01*
G02X26911I-3404J-3597D01*
G01X26957Y408405D01*
X26982Y408528D01*
X26779Y408990D01*
X26671Y409055D01*
X26607Y409050D01*
G02X26378Y409042I-226J3194D01*
G02X29580Y412244I0J3202D01*
G02X28881Y410247I-3202J0D01*
G01X28841Y410197D01*
X28833Y410071D01*
X29099Y409642D01*
X29215Y409593D01*
X29277Y409606D01*
G02X31353I1038J-4842D01*
G01X31415Y409593D01*
X31531Y409642D01*
X31797Y410071D01*
X31789Y410197D01*
G37*
G36*
G01X146662Y891696D02*
G02X146362Y893115I3202J1418D01*
G02X146662Y894534I3502J1D01*
G03Y894696I-182J81D01*
G02X146362Y896115I3202J1418D01*
G02X149864Y899617I3502J0D01*
G02X151046Y899411I-1J-3502D01*
G03X151182I68J189D01*
G02X152364Y899617I1183J-3296D01*
G02X155866Y896115I0J-3502D01*
G02X155566Y894696I-3502J-1D01*
G03Y894534I182J-81D01*
G02X155866Y893115I-3202J-1418D01*
G02X155566Y891696I-3502J-1D01*
G03Y891534I182J-81D01*
G02X155866Y890115I-3202J-1418D01*
G02X152364Y886613I-3502J0D01*
G02X151182Y886819I1J3502D01*
G03X151046I-68J-189D01*
G02X149864Y886613I-1183J3296D01*
G02X146362Y890115I0J3502D01*
G02X146662Y891534I3502J1D01*
G03Y891696I-182J81D01*
G37*
G36*
G01X179418Y897257D02*
Y897573D01*
G03X179341Y897730I-200J-1D01*
G02X178762Y898915I923J1185D01*
G02X181766I1502J0D01*
G02X181187Y897730I-1502J0D01*
G03X181110Y897573I123J-158D01*
G01Y897257D01*
G03X181187Y897100I200J1D01*
G02Y894730I-923J-1185D01*
G03X181110Y894573I123J-158D01*
G01Y894257D01*
G03X181187Y894100I200J1D01*
G02Y891730I-923J-1185D01*
G03X181110Y891573I123J-158D01*
G01Y891257D01*
G03X181187Y891100I200J1D01*
G02X181766Y889915I-923J-1185D01*
G02X178762I-1502J0D01*
G02X179341Y891100I1502J0D01*
G03X179418Y891257I-123J158D01*
G01Y891573D01*
G03X179341Y891730I-200J-1D01*
G02Y894100I923J1185D01*
G03X179418Y894257I-123J158D01*
G01Y894573D01*
G03X179341Y894730I-200J-1D01*
G02Y897100I923J1185D01*
G03X179418Y897257I-123J158D01*
G37*
G36*
G01X193118Y897357D02*
Y897673D01*
G03X193041Y897830I-200J-1D01*
G02X192462Y899015I923J1185D01*
G02X195466I1502J0D01*
G02X194887Y897830I-1502J0D01*
G03X194810Y897673I123J-158D01*
G01Y897357D01*
G03X194887Y897200I200J1D01*
G02Y894830I-923J-1185D01*
G03X194810Y894673I123J-158D01*
G01Y894357D01*
G03X194887Y894200I200J1D01*
G02Y891830I-923J-1185D01*
G03X194810Y891673I123J-158D01*
G01Y891357D01*
G03X194887Y891200I200J1D01*
G02Y888830I-923J-1185D01*
G03X194810Y888673I123J-158D01*
G01Y888357D01*
G03X194887Y888200I200J1D01*
G02X195466Y887015I-923J-1185D01*
G02X192462I-1502J0D01*
G02X193041Y888200I1502J0D01*
G03X193118Y888357I-123J158D01*
G01Y888673D01*
G03X193041Y888830I-200J-1D01*
G02Y891200I923J1185D01*
G03X193118Y891357I-123J158D01*
G01Y891673D01*
G03X193041Y891830I-200J-1D01*
G02Y894200I923J1185D01*
G03X193118Y894357I-123J158D01*
G01Y894673D01*
G03X193041Y894830I-200J-1D01*
G02Y897200I923J1185D01*
G03X193118Y897357I-123J158D01*
G37*
G36*
G01X35727Y905660D02*
G02X36027Y904241I-3202J-1418D01*
G02X29023I-3502J0D01*
G02X29323Y905660I3502J1D01*
G03Y905822I-182J81D01*
G02X29023Y907241I3202J1418D01*
G02X36027I3502J0D01*
G02X35727Y905822I-3502J-1D01*
G03Y905660I182J-81D01*
G37*
G36*
G01X183531Y911842D02*
Y912158D01*
G03X183454Y912315I-200J-1D01*
G02X182875Y913500I923J1185D01*
G02X185879I1502J0D01*
G02X185300Y912315I-1502J0D01*
G03X185223Y912158I123J-158D01*
G01Y911842D01*
G03X185300Y911685I200J1D01*
G02X185879Y910500I-923J-1185D01*
G02X182875I-1502J0D01*
G02X183454Y911685I1502J0D01*
G03X183531Y911842I-123J158D01*
G37*
G36*
G01X166079Y911919D02*
G02X166379Y910500I-3202J-1418D01*
G02X159375I-3502J0D01*
G02X159675Y911919I3502J1D01*
G03Y912081I-182J81D01*
G02X159375Y913500I3202J1418D01*
G02X166379I3502J0D01*
G02X166079Y912081I-3502J-1D01*
G03Y911919I182J-81D01*
G37*
G36*
G01X183531Y922842D02*
Y923158D01*
G03X183454Y923315I-200J-1D01*
G02X182875Y924500I923J1185D01*
G02X185879I1502J0D01*
G02X185300Y923315I-1502J0D01*
G03X185223Y923158I123J-158D01*
G01Y922842D01*
G03X185300Y922685I200J1D01*
G02X185879Y921500I-923J-1185D01*
G02X182875I-1502J0D01*
G02X183454Y922685I1502J0D01*
G03X183531Y922842I-123J158D01*
G37*
G36*
G01Y932842D02*
Y933158D01*
G03X183454Y933315I-200J-1D01*
G02X182875Y934500I923J1185D01*
G02X185879I1502J0D01*
G02X185300Y933315I-1502J0D01*
G03X185223Y933158I123J-158D01*
G01Y932842D01*
G03X185300Y932685I200J1D01*
G02X185879Y931500I-923J-1185D01*
G02X182875I-1502J0D01*
G02X183454Y932685I1502J0D01*
G03X183531Y932842I-123J158D01*
G37*
G36*
G01X161329Y928359D02*
G02X159375Y931500I1548J3141D01*
G02X159675Y932919I3502J1D01*
G03Y933081I-182J81D01*
G02X159375Y934500I3202J1418D01*
G02X166379I3502J0D01*
G02X166079Y933081I-3502J-1D01*
G03Y932919I182J-81D01*
G02X166379Y931500I-3202J-1418D01*
G02X164425Y928359I-3502J0D01*
G03X164314Y928179I89J-179D01*
G01Y927821D01*
G03X164425Y927641I200J-1D01*
G02X166379Y924500I-1548J-3141D01*
G02X166079Y923081I-3502J-1D01*
G03Y922919I182J-81D01*
G02X166379Y921500I-3202J-1418D01*
G02X159375I-3502J0D01*
G02X159675Y922919I3502J1D01*
G03Y923081I-182J81D01*
G02X159375Y924500I3202J1418D01*
G02X161329Y927641I3502J0D01*
G03X161440Y927821I-89J179D01*
G01Y928179D01*
G03X161329Y928359I-200J1D01*
G37*
G36*
G01X30789Y936234D02*
G02X31089Y934815I-3202J-1418D01*
G02X24085I-3502J0D01*
G02X24385Y936234I3502J1D01*
G03Y936396I-182J81D01*
G02X24085Y937815I3202J1418D01*
G02X31089I3502J0D01*
G02X30789Y936396I-3502J-1D01*
G03Y936234I182J-81D01*
G37*
G36*
G01X182331Y941442D02*
Y941758D01*
G03X182254Y941915I-200J-1D01*
G02X181675Y943100I923J1185D01*
G02X184679I1502J0D01*
G02X184100Y941915I-1502J0D01*
G03X184023Y941758I123J-158D01*
G01Y941442D01*
G03X184100Y941285I200J1D01*
G02X184679Y940100I-923J-1185D01*
G02X181675I-1502J0D01*
G02X182254Y941285I1502J0D01*
G03X182331Y941442I-123J158D01*
G37*
G36*
G01X134982Y960683D02*
G02X134776Y961865I3296J1183D01*
G02X138278Y965367I3502J0D01*
G02X139460Y965161I-1J-3502D01*
G03X139596I68J189D01*
G02X140778Y965367I1183J-3296D01*
G02X141998Y965148I1J-3502D01*
G03X142138I70J187D01*
G02X143358Y965367I1219J-3283D01*
G02X146860Y961865I0J-3502D01*
G02X146654Y960683I-3502J1D01*
G03Y960547I189J-68D01*
G02X146860Y959365I-3296J-1183D01*
G02X143358Y955863I-3502J0D01*
G02X142157Y956076I2J3502D01*
G03X142019I-69J-188D01*
G02X140818Y955863I-1203J3289D01*
G02X139617Y956076I2J3502D01*
G03X139479I-69J-188D01*
G02X138278Y955863I-1203J3289D01*
G02X134776Y959365I0J3502D01*
G02X134982Y960547I3502J-1D01*
G03Y960683I-189J68D01*
G37*
G36*
G01X147786Y963832D02*
G02X147580Y965014I3296J1183D01*
G02X151082Y968516I3502J0D01*
G02X152264Y968310I-1J-3502D01*
G03X152400I68J189D01*
G02X153582Y968516I1183J-3296D01*
G02X154802Y968297I1J-3502D01*
G03X154942I70J187D01*
G02X156162Y968516I1219J-3283D01*
G02X159664Y965014I0J-3502D01*
G02X159458Y963832I-3502J1D01*
G03Y963696I189J-68D01*
G02X159664Y962514I-3296J-1183D01*
G02X156162Y959012I-3502J0D01*
G02X154961Y959225I2J3502D01*
G03X154823I-69J-188D01*
G02X153622Y959012I-1203J3289D01*
G02X152421Y959225I2J3502D01*
G03X152283I-69J-188D01*
G02X151082Y959012I-1203J3289D01*
G02X147580Y962514I0J3502D01*
G02X147786Y963696I3502J-1D01*
G03Y963832I-189J68D01*
G37*
G36*
G01X41025Y971954D02*
X40709D01*
G03X40552Y971877I1J-200D01*
G02X39367Y971298I-1185J923D01*
G02Y974302I0J1502D01*
G02X40552Y973723I0J-1502D01*
G03X40709Y973646I158J123D01*
G01X41025D01*
G03X41182Y973723I-1J200D01*
G02X42367Y974302I1185J-923D01*
G02Y971298I0J-1502D01*
G02X41182Y971877I0J1502D01*
G03X41025Y971954I-158J-123D01*
G37*
G36*
G01X166416Y975654D02*
X166100D01*
G03X165943Y975577I1J-200D01*
G02X164758Y974998I-1185J923D01*
G02Y978002I0J1502D01*
G02X165943Y977423I0J-1502D01*
G03X166100Y977346I158J123D01*
G01X166416D01*
G03X166573Y977423I-1J200D01*
G02X167758Y978002I1185J-923D01*
G02Y974998I0J-1502D01*
G02X166573Y975577I0J1502D01*
G03X166416Y975654I-158J-123D01*
G37*
G36*
G01X47818Y992457D02*
Y992773D01*
G03X47741Y992930I-200J-1D01*
G02X47162Y994115I923J1185D01*
G02X48664Y995617I1502J0D01*
G02X49651Y995247I0J-1501D01*
G01X49679Y995223D01*
X49746Y995198D01*
X50082D01*
X50149Y995223D01*
X50177Y995247D01*
G02X51164Y995617I987J-1131D01*
G02X52666Y994115I0J-1502D01*
G02X52087Y992930I-1502J0D01*
G03X52010Y992773I123J-158D01*
G01Y992457D01*
G03X52087Y992300I200J1D01*
G02Y989930I-923J-1185D01*
G03X52010Y989773I123J-158D01*
G01Y989457D01*
G03X52087Y989300I200J1D01*
G02Y986930I-923J-1185D01*
G03X52010Y986773I123J-158D01*
G01Y986457D01*
G03X52087Y986300I200J1D01*
G02X52666Y985115I-923J-1185D01*
G02X51164Y983613I-1502J0D01*
G02X50177Y983983I0J1501D01*
G01X50149Y984007D01*
X50082Y984032D01*
X49746D01*
X49679Y984007D01*
X49651Y983983D01*
G02X48664Y983613I-987J1131D01*
G02X47162Y985115I0J1502D01*
G02X47741Y986300I1502J0D01*
G03X47818Y986457I-123J158D01*
G01Y986773D01*
G03X47741Y986930I-200J-1D01*
G02Y989300I923J1185D01*
G03X47818Y989457I-123J158D01*
G01Y989773D01*
G03X47741Y989930I-200J-1D01*
G02Y992300I923J1185D01*
G03X47818Y992457I-123J158D01*
G37*
G36*
G01X60709Y997246D02*
X61025D01*
G03X61182Y997323I-1J200D01*
G02X63552I1185J-923D01*
G03X63709Y997246I158J123D01*
G01X64025D01*
G03X64182Y997323I-1J200D01*
G02X65367Y997902I1185J-923D01*
G02Y994898I0J-1502D01*
G02X64182Y995477I0J1502D01*
G03X64025Y995554I-158J-123D01*
G01X63709D01*
G03X63552Y995477I1J-200D01*
G02X61182I-1185J923D01*
G03X61025Y995554I-158J-123D01*
G01X60709D01*
G03X60552Y995477I1J-200D01*
G02X58182I-1185J923D01*
G03X58025Y995554I-158J-123D01*
G01X57709D01*
G03X57552Y995477I1J-200D01*
G02X56367Y994898I-1185J923D01*
G02Y997902I0J1502D01*
G02X57552Y997323I0J-1502D01*
G03X57709Y997246I158J123D01*
G01X58025D01*
G03X58182Y997323I-1J200D01*
G02X60552I1185J-923D01*
G03X60709Y997246I158J123D01*
G37*
G36*
G01X186000Y998846D02*
X186316D01*
G03X186473Y998923I-1J200D01*
G02X187658Y999502I1185J-923D01*
G02X188645Y999132I0J-1501D01*
G01X188673Y999108D01*
X188740Y999083D01*
X189076D01*
X189143Y999108D01*
X189171Y999132D01*
G02X190158Y999502I987J-1131D01*
G02X191660Y998000I0J-1502D01*
G02X191081Y996815I-1502J0D01*
G03X191004Y996658I123J-158D01*
G01Y996342D01*
G03X191081Y996185I200J1D01*
G02X191660Y995000I-923J-1185D01*
G02X190158Y993498I-1502J0D01*
G02X189171Y993868I0J1501D01*
G01X189143Y993892D01*
X189076Y993917D01*
X188740D01*
X188673Y993892D01*
X188645Y993868D01*
G02X187658Y993498I-987J1131D01*
G02X186473Y994077I0J1502D01*
G03X186316Y994154I-158J-123D01*
G01X186000D01*
G03X185843Y994077I1J-200D01*
G02X183473I-1185J923D01*
G03X183316Y994154I-158J-123D01*
G01X183000D01*
G03X182843Y994077I1J-200D01*
G02X181658Y993498I-1185J923D01*
G02X180156Y995000I0J1502D01*
G02X180735Y996185I1502J0D01*
G03X180812Y996342I-123J158D01*
G01Y996658D01*
G03X180735Y996815I-200J-1D01*
G02X180156Y998000I923J1185D01*
G02X181658Y999502I1502J0D01*
G02X182843Y998923I0J-1502D01*
G03X183000Y998846I158J123D01*
G01X183316D01*
G03X183473Y998923I-1J200D01*
G02X185843I1185J-923D01*
G03X186000Y998846I158J123D01*
G37*
G36*
G01X21327Y1016646D02*
X21643D01*
G03X21800Y1016723I-1J200D01*
G02X24170I1185J-923D01*
G03X24327Y1016646I158J123D01*
G01X24643D01*
G03X24800Y1016723I-1J200D01*
G02X25985Y1017302I1185J-923D01*
G02X27487Y1015800I0J-1502D01*
G02X26908Y1014615I-1502J0D01*
G03X26831Y1014458I123J-158D01*
G01Y1014142D01*
G03X26908Y1013985I200J1D01*
G02X27487Y1012800I-923J-1185D01*
G02X25985Y1011298I-1502J0D01*
G02X24800Y1011877I0J1502D01*
G03X24643Y1011954I-158J-123D01*
G01X24327D01*
G03X24170Y1011877I1J-200D01*
G02X21800I-1185J923D01*
G03X21643Y1011954I-158J-123D01*
G01X21327D01*
G03X21170Y1011877I1J-200D01*
G02X18800I-1185J923D01*
G03X18643Y1011954I-158J-123D01*
G01X18327D01*
G03X18170Y1011877I1J-200D01*
G02X16985Y1011298I-1185J923D01*
G02X15483Y1012800I0J1502D01*
G02X16062Y1013985I1502J0D01*
G03X16139Y1014142I-123J158D01*
G01Y1014458D01*
G03X16062Y1014615I-200J-1D01*
G02X15483Y1015800I923J1185D01*
G02X16985Y1017302I1502J0D01*
G02X18170Y1016723I0J-1502D01*
G03X18327Y1016646I158J123D01*
G01X18643D01*
G03X18800Y1016723I-1J200D01*
G02X21170I1185J-923D01*
G03X21327Y1016646I158J123D01*
G37*
G36*
G01X130224Y1016746D02*
X130540D01*
G03X130697Y1016823I-1J200D01*
G02X133067I1185J-923D01*
G03X133224Y1016746I158J123D01*
G01X133540D01*
G03X133697Y1016823I-1J200D01*
G02X134882Y1017402I1185J-923D01*
G02X136384Y1015900I0J-1502D01*
G02X135805Y1014715I-1502J0D01*
G03X135728Y1014558I123J-158D01*
G01Y1014242D01*
G03X135805Y1014085I200J1D01*
G02X136384Y1012900I-923J-1185D01*
G02X134882Y1011398I-1502J0D01*
G02X133697Y1011977I0J1502D01*
G03X133540Y1012054I-158J-123D01*
G01X133224D01*
G03X133067Y1011977I1J-200D01*
G02X130697I-1185J923D01*
G03X130540Y1012054I-158J-123D01*
G01X130224D01*
G03X130067Y1011977I1J-200D01*
G02X127697I-1185J923D01*
G03X127540Y1012054I-158J-123D01*
G01X127224D01*
G03X127067Y1011977I1J-200D01*
G02X125882Y1011398I-1185J923D01*
G02X124380Y1012900I0J1502D01*
G02X124959Y1014085I1502J0D01*
G03X125036Y1014242I-123J158D01*
G01Y1014558D01*
G03X124959Y1014715I-200J-1D01*
G02X124380Y1015900I923J1185D01*
G02X125882Y1017402I1502J0D01*
G02X127067Y1016823I0J-1502D01*
G03X127224Y1016746I158J123D01*
G01X127540D01*
G03X127697Y1016823I-1J200D01*
G02X130067I1185J-923D01*
G03X130224Y1016746I158J123D01*
G37*
G36*
G01X39213Y1026322D02*
X38897D01*
G03X38740Y1026245I1J-200D01*
G02X37555Y1025666I-1185J923D01*
G02Y1028670I0J1502D01*
G02X38740Y1028091I0J-1502D01*
G03X38897Y1028014I158J123D01*
G01X39213D01*
G03X39370Y1028091I-1J200D01*
G02X40555Y1028670I1185J-923D01*
G02Y1025666I0J-1502D01*
G02X39370Y1026245I0J1502D01*
G03X39213Y1026322I-158J-123D01*
G37*
G36*
G01X148140Y1027654D02*
X147824D01*
G03X147667Y1027577I1J-200D01*
G02X146482Y1026998I-1185J923D01*
G02Y1030002I0J1502D01*
G02X147667Y1029423I0J-1502D01*
G03X147824Y1029346I158J123D01*
G01X148140D01*
G03X148297Y1029423I-1J200D01*
G02X149482Y1030002I1185J-923D01*
G02Y1026998I0J-1502D01*
G02X148297Y1027577I0J1502D01*
G03X148140Y1027654I-158J-123D01*
G37*
G36*
G01X21327Y1029646D02*
X21643D01*
G03X21800Y1029723I-1J200D01*
G02X24170I1185J-923D01*
G03X24327Y1029646I158J123D01*
G01X24643D01*
G03X24800Y1029723I-1J200D01*
G02X25985Y1030302I1185J-923D01*
G02Y1027298I0J-1502D01*
G02X24800Y1027877I0J1502D01*
G03X24643Y1027954I-158J-123D01*
G01X24327D01*
G03X24170Y1027877I1J-200D01*
G02X21800I-1185J923D01*
G03X21643Y1027954I-158J-123D01*
G01X21327D01*
G03X21170Y1027877I1J-200D01*
G02X18800I-1185J923D01*
G03X18643Y1027954I-158J-123D01*
G01X18327D01*
G03X18170Y1027877I1J-200D01*
G02X16985Y1027298I-1185J923D01*
G02Y1030302I0J1502D01*
G02X18170Y1029723I0J-1502D01*
G03X18327Y1029646I158J123D01*
G01X18643D01*
G03X18800Y1029723I-1J200D01*
G02X21170I1185J-923D01*
G03X21327Y1029646I158J123D01*
G37*
G36*
G01X39166Y1044502D02*
G02X40585Y1044802I1418J-3202D01*
G02Y1037798I0J-3502D01*
G02X39166Y1038098I-1J3502D01*
G03X39004I-81J-182D01*
G02X37585Y1037798I-1418J3202D01*
G02Y1044802I0J3502D01*
G02X39004Y1044502I1J-3502D01*
G03X39166I81J182D01*
G37*
G36*
G01X123980Y1040581D02*
G02X123680Y1042000I3202J1418D01*
G02X127182Y1045502I3502J0D01*
G02X128696Y1045158I0J-3502D01*
G03X128868I86J180D01*
G02X130382Y1045502I1514J-3158D01*
G02X131801Y1045202I1J-3502D01*
G03X131963I81J182D01*
G02X133382Y1045502I1418J-3202D01*
G02X136884Y1042000I0J-3502D01*
G02X136584Y1040581I-3502J-1D01*
G03Y1040419I182J-81D01*
G02X136884Y1039000I-3202J-1418D01*
G02X133382Y1035498I-3502J0D01*
G02X131963Y1035798I-1J3502D01*
G03X131801I-81J-182D01*
G02X130382Y1035498I-1418J3202D01*
G02X128868Y1035842I0J3502D01*
G03X128696I-86J-180D01*
G02X127182Y1035498I-1514J3158D01*
G02X123680Y1039000I0J3502D01*
G02X123980Y1040419I3502J1D01*
G03Y1040581I-182J81D01*
G37*
G36*
G01X148063Y1046202D02*
G02X149482Y1046502I1418J-3202D01*
G02Y1039498I0J-3502D01*
G02X148063Y1039798I-1J3502D01*
G03X147901I-81J-182D01*
G02X146482Y1039498I-1418J3202D01*
G02Y1046502I0J3502D01*
G02X147901Y1046202I1J-3502D01*
G03X148063I81J182D01*
G37*
G36*
G01X10209Y1048036D02*
G02X9990Y1049256I3283J1219D01*
G02X10196Y1050438I3502J-1D01*
G03Y1050574I-189J68D01*
G02X9990Y1051756I3296J1183D01*
G02X16994I3502J0D01*
G02X16788Y1050574I-3502J1D01*
G03Y1050438I189J-68D01*
G02X16994Y1049256I-3296J-1183D01*
G02X16775Y1048036I-3502J-1D01*
G03Y1047896I187J-70D01*
G02X16994Y1046676I-3283J-1219D01*
G02X16881Y1045793I-3502J-1D01*
G01X16868Y1045742D01*
X16894Y1045641D01*
X17210Y1045320D01*
X17310Y1045291D01*
X17362Y1045304D01*
G02X18185Y1045402I823J-3404D01*
G02X19699Y1045058I0J-3502D01*
G03X19871I86J180D01*
G02X21385Y1045402I1514J-3158D01*
G02X23041Y1044986I0J-3502D01*
G03X23219Y1044980I95J176D01*
G02X24685Y1045302I1467J-3180D01*
G02X28187Y1041800I0J-3502D01*
G02X27887Y1040381I-3502J-1D01*
G03Y1040219I182J-81D01*
G02X28187Y1038800I-3202J-1418D01*
G02X24685Y1035298I-3502J0D01*
G02X23029Y1035714I0J3502D01*
G03X22851Y1035720I-95J-176D01*
G02X21385Y1035398I-1467J3180D01*
G02X19871Y1035742I0J3502D01*
G03X19699I-86J-180D01*
G02X18185Y1035398I-1514J3158D01*
G02X14683Y1038900I0J3502D01*
G02X14983Y1040319I3502J1D01*
G03Y1040481I-182J81D01*
G02X14683Y1041900I3202J1418D01*
G02X14796Y1042783I3502J1D01*
G01X14809Y1042834D01*
X14783Y1042935D01*
X14467Y1043256D01*
X14367Y1043285D01*
X14315Y1043272D01*
G02X13492Y1043174I-823J3404D01*
G02X9990Y1046676I0J3502D01*
G02X10209Y1047896I3502J1D01*
G03Y1048036I-187J70D01*
G37*
G36*
G01X128696Y1051842D02*
G02X127182Y1051498I-1514J3158D01*
G02Y1058502I0J3502D01*
G02X128696Y1058158I0J-3502D01*
G03X128868I86J180D01*
G02X130382Y1058502I1514J-3158D01*
G02X131801Y1058202I1J-3502D01*
G03X131963I81J182D01*
G02X133382Y1058502I1418J-3202D01*
G02Y1051498I0J-3502D01*
G02X131963Y1051798I-1J3502D01*
G03X131801I-81J-182D01*
G02X130382Y1051498I-1418J3202D01*
G02X128868Y1051842I0J3502D01*
G03X128696I-86J-180D01*
G37*
G36*
G01X21342Y1063566D02*
X21658D01*
G03X21815Y1063643I-1J200D01*
G02X24185I1185J-923D01*
G03X24342Y1063566I158J123D01*
G01X24658D01*
G03X24815Y1063643I-1J200D01*
G02X26000Y1064222I1185J-923D01*
G02Y1061218I0J-1502D01*
G02X24815Y1061797I0J1502D01*
G03X24658Y1061874I-158J-123D01*
G01X24342D01*
G03X24185Y1061797I1J-200D01*
G02X21815I-1185J923D01*
G03X21658Y1061874I-158J-123D01*
G01X21342D01*
G03X21185Y1061797I1J-200D01*
G02X18815I-1185J923D01*
G03X18658Y1061874I-158J-123D01*
G01X18342D01*
G03X18185Y1061797I1J-200D01*
G02X15815I-1185J923D01*
G03X15658Y1061874I-158J-123D01*
G01X15342D01*
G03X15185Y1061797I1J-200D01*
G02X14000Y1061218I-1185J923D01*
G02Y1064222I0J1502D01*
G02X15185Y1063643I0J-1502D01*
G03X15342Y1063566I158J123D01*
G01X15658D01*
G03X15815Y1063643I-1J200D01*
G02X18185I1185J-923D01*
G03X18342Y1063566I158J123D01*
G01X18658D01*
G03X18815Y1063643I-1J200D01*
G02X21185I1185J-923D01*
G03X21342Y1063566I158J123D01*
G37*
G36*
G01X185700Y1063610D02*
X186016D01*
G03X186173Y1063687I-1J200D01*
G02X188543I1185J-923D01*
G03X188700Y1063610I158J123D01*
G01X189016D01*
G03X189173Y1063687I-1J200D01*
G02X190358Y1064266I1185J-923D01*
G02X191860Y1062764I0J-1502D01*
G02X191416Y1061698I-1502J0D01*
G01X191387Y1061670D01*
X191357Y1061596D01*
Y1061232D01*
X191387Y1061158D01*
X191416Y1061130D01*
G02X191860Y1060064I-1058J-1066D01*
G02X190358Y1058562I-1502J0D01*
G02X189173Y1059141I0J1502D01*
G03X189016Y1059218I-158J-123D01*
G01X188700D01*
G03X188543Y1059141I1J-200D01*
G02X186173I-1185J923D01*
G03X186016Y1059218I-158J-123D01*
G01X185700D01*
G03X185543Y1059141I1J-200D01*
G02X183173I-1185J923D01*
G03X183016Y1059218I-158J-123D01*
G01X182700D01*
G03X182543Y1059141I1J-200D01*
G02X181358Y1058562I-1185J923D01*
G02X179856Y1060064I0J1502D01*
G02X180300Y1061130I1502J0D01*
G01X180329Y1061158D01*
X180359Y1061232D01*
Y1061596D01*
X180329Y1061670D01*
X180300Y1061698D01*
G02X179856Y1062764I1058J1066D01*
G02X181358Y1064266I1502J0D01*
G02X182543Y1063687I0J-1502D01*
G03X182700Y1063610I158J123D01*
G01X183016D01*
G03X183173Y1063687I-1J200D01*
G02X185543I1185J-923D01*
G03X185700Y1063610I158J123D01*
G37*
G36*
G01X119989Y1076082D02*
Y1076418D01*
X119964Y1076485D01*
X119940Y1076513D01*
G02X119570Y1077500I1131J987D01*
G02X122574I1502J0D01*
G02X122204Y1076513I-1501J0D01*
G01X122180Y1076485D01*
X122155Y1076418D01*
Y1076082D01*
X122180Y1076015D01*
X122204Y1075987D01*
G02Y1074013I-1131J-987D01*
G01X122180Y1073985D01*
X122155Y1073918D01*
Y1073582D01*
X122180Y1073515D01*
X122204Y1073487D01*
G02X122574Y1072500I-1131J-987D01*
G02X119570I-1502J0D01*
G02X119940Y1073487I1501J0D01*
G01X119964Y1073515D01*
X119989Y1073582D01*
Y1073918D01*
X119964Y1073985D01*
X119940Y1074013D01*
G02Y1075987I1131J987D01*
G01X119964Y1076015D01*
X119989Y1076082D01*
G37*
G36*
G01X139776Y1074318D02*
G02X139570Y1075500I3296J1183D01*
G02X139776Y1076682I3502J-1D01*
G03Y1076818I-189J68D01*
G02X139570Y1078000I3296J1183D01*
G02X146574I3502J0D01*
G02X146368Y1076818I-3502J1D01*
G03Y1076682I189J-68D01*
G02X146574Y1075500I-3296J-1183D01*
G02X146368Y1074318I-3502J1D01*
G03Y1074182I189J-68D01*
G02X146574Y1073000I-3296J-1183D01*
G02X145135Y1070170I-3502J0D01*
G03X145054Y1070030I118J-162D01*
G02X144868Y1069218I-3482J370D01*
G03Y1069082I189J-68D01*
G02X145074Y1067900I-3296J-1183D01*
G02X138070I-3502J0D01*
G02X138276Y1069082I3502J-1D01*
G03Y1069218I-189J68D01*
G02X138070Y1070400I3296J1183D01*
G02X139509Y1073230I3502J0D01*
G03X139590Y1073370I-118J162D01*
G02X139776Y1074182I3482J-370D01*
G03Y1074318I-189J68D01*
G37*
G36*
G01X52759Y1073977D02*
G02X52198Y1075878I2940J1901D01*
G02X52592Y1077491I3502J-1D01*
G03Y1077676I-178J92D01*
G02X52198Y1079289I3108J1614D01*
G02X59202I3502J0D01*
G02X58808Y1077676I-3502J1D01*
G03Y1077491I178J-93D01*
G02X59202Y1075878I-3108J-1614D01*
G02X58642Y1073978I-3503J0D01*
G03Y1073761I168J-109D01*
G02X59203Y1071860I-2940J-1901D01*
G02X58809Y1070247I-3502J1D01*
G03Y1070062I178J-93D01*
G02X59203Y1068449I-3108J-1614D01*
G02X59148Y1067831I-3502J0D01*
G01X59138Y1067776D01*
X59176Y1067675D01*
X59536Y1067385D01*
X59643Y1067369D01*
X59694Y1067391D01*
G02X61029Y1067655I1334J-3238D01*
G02X64531Y1064153I0J-3502D01*
G02X64137Y1062540I-3502J1D01*
G03Y1062355I178J-92D01*
G02X64531Y1060742I-3108J-1614D01*
G02X57527I-3502J0D01*
G02X57921Y1062355I3502J-1D01*
G03Y1062540I-178J93D01*
G02X57527Y1064153I3108J1614D01*
G02X57582Y1064771I3502J0D01*
G01X57592Y1064826D01*
X57554Y1064927D01*
X57194Y1065217D01*
X57087Y1065233D01*
X57036Y1065211D01*
G02X55701Y1064947I-1334J3238D01*
G02X52199Y1068449I0J3502D01*
G02X52593Y1070062I3502J-1D01*
G03Y1070247I-178J92D01*
G02X52199Y1071860I3108J1614D01*
G02X52759Y1073760I3503J0D01*
G03Y1073977I-168J108D01*
G37*
G36*
G01X58743Y1092278D02*
G02X59137Y1090665I-3108J-1614D01*
G02X52133I-3502J0D01*
G02X52527Y1092278I3502J-1D01*
G03Y1092463I-178J92D01*
G02X52133Y1094076I3108J1614D01*
G02X59137I3502J0D01*
G02X58743Y1092463I-3502J1D01*
G03Y1092278I178J-92D01*
G37*
G36*
G01X119989Y1095582D02*
Y1095918D01*
X119964Y1095985D01*
X119940Y1096013D01*
G02X119570Y1097000I1131J987D01*
G02X122574I1502J0D01*
G02X122204Y1096013I-1501J0D01*
G01X122180Y1095985D01*
X122155Y1095918D01*
Y1095582D01*
X122180Y1095515D01*
X122204Y1095487D01*
G02Y1093513I-1131J-987D01*
G01X122180Y1093485D01*
X122155Y1093418D01*
Y1093082D01*
X122180Y1093015D01*
X122204Y1092987D01*
G02X122574Y1092000I-1131J-987D01*
G02X119570I-1502J0D01*
G02X119940Y1092987I1501J0D01*
G01X119964Y1093015D01*
X119989Y1093082D01*
Y1093418D01*
X119964Y1093485D01*
X119940Y1093513D01*
G02Y1095487I1131J987D01*
G01X119964Y1095515D01*
X119989Y1095582D01*
G37*
G36*
G01X139776Y1093818D02*
G02X139570Y1095000I3296J1183D01*
G02X139776Y1096182I3502J-1D01*
G03Y1096318I-189J68D01*
G02X139570Y1097500I3296J1183D01*
G02X146574I3502J0D01*
G02X146368Y1096318I-3502J1D01*
G03Y1096182I189J-68D01*
G02X146574Y1095000I-3296J-1183D01*
G02X146368Y1093818I-3502J1D01*
G03Y1093682I189J-68D01*
G02X146574Y1092500I-3296J-1183D01*
G02X139570I-3502J0D01*
G02X139776Y1093682I3502J-1D01*
G03Y1093818I-189J68D01*
G37*
G36*
G01X177256Y1105243D02*
G02X176956Y1106662I3202J1418D01*
G02X180458Y1110164I3502J0D01*
G02X181877Y1109864I1J-3502D01*
G03X182039I81J182D01*
G02X183458Y1110164I1418J-3202D01*
G02X184877Y1109864I1J-3502D01*
G03X185039I81J182D01*
G02X186458Y1110164I1418J-3202D01*
G02X189960Y1106662I0J-3502D01*
G02X189660Y1105243I-3502J-1D01*
G03Y1105081I182J-81D01*
G02X189960Y1103662I-3202J-1418D01*
G02X186458Y1100160I-3502J0D01*
G02X185039Y1100460I-1J3502D01*
G03X184877I-81J-182D01*
G02X183458Y1100160I-1418J3202D01*
G02X182039Y1100460I-1J3502D01*
G03X181877I-81J-182D01*
G02X180458Y1100160I-1418J3202D01*
G02X176956Y1103662I0J3502D01*
G02X177256Y1105081I3502J1D01*
G03Y1105243I-182J81D01*
G37*
G36*
G01X15798Y1105881D02*
G02X15498Y1107300I3202J1418D01*
G02X19000Y1110802I3502J0D01*
G02X20419Y1110502I1J-3502D01*
G03X20581I81J182D01*
G02X22000Y1110802I1418J-3202D01*
G02X23419Y1110502I1J-3502D01*
G03X23581I81J182D01*
G02X25000Y1110802I1418J-3202D01*
G02X28502Y1107300I0J-3502D01*
G02X28202Y1105881I-3502J-1D01*
G03Y1105719I182J-81D01*
G02X28502Y1104300I-3202J-1418D01*
G02X25000Y1100798I-3502J0D01*
G02X23581Y1101098I-1J3502D01*
G03X23419I-81J-182D01*
G02X22000Y1100798I-1418J3202D01*
G02X20581Y1101098I-1J3502D01*
G03X20419I-81J-182D01*
G02X19000Y1100798I-1418J3202D01*
G02X15498Y1104300I0J3502D01*
G02X15798Y1105719I3502J1D01*
G03Y1105881I-182J81D01*
G37*
G36*
G01X24347Y1183231D02*
X24406Y1183670D01*
X24369Y1183766D01*
X24329Y1183799D01*
G02X23176Y1186260I2050J2461D01*
G02X29580I3202J0D01*
G02X28427Y1183799I-3203J0D01*
G01X28387Y1183766D01*
X28350Y1183670D01*
X28409Y1183231D01*
X28471Y1183149D01*
X28518Y1183127D01*
G02X31119Y1180526I-2140J-4741D01*
G01X31141Y1180479D01*
X31223Y1180417D01*
X31662Y1180358D01*
X31758Y1180395D01*
X31791Y1180435D01*
G02X34252Y1181588I2461J-2050D01*
G02X37454Y1178386I0J-3202D01*
G02X36301Y1175925I-3203J0D01*
G01X36261Y1175892D01*
X36224Y1175796D01*
X36283Y1175357D01*
X36345Y1175275D01*
X36392Y1175253D01*
G02Y1165771I-2139J-4741D01*
G01X36345Y1165749D01*
X36283Y1165667D01*
X36224Y1165228D01*
X36261Y1165132D01*
X36301Y1165099D01*
G02X37454Y1162638I-2050J-2461D01*
G02X36623Y1160486I-3202J0D01*
G01X36597Y1160458D01*
X36571Y1160390D01*
Y1160352D01*
G03X36771Y1160152I200J0D01*
G01X36816D01*
G03X36957Y1160210I0J200D01*
G01X38990Y1162243D01*
G03X39048Y1162384I-142J141D01*
G01Y1163613D01*
X39043Y1163637D01*
G02X38998Y1164000I1457J365D01*
G02X42002I1502J0D01*
G02X41957Y1163637I-1502J2D01*
G01X41952Y1163613D01*
Y1161700D01*
G02X41526Y1160674I-1451J1D01*
G01X38526Y1157674D01*
G02X37500Y1157248I-1027J1025D01*
G01X37190D01*
G03X37012Y1157140I-1J-200D01*
G01X36823Y1156774D01*
X36830Y1156663D01*
X36863Y1156617D01*
G02X37454Y1154764I-2611J-1853D01*
G02X34252Y1151562I-3202J0D01*
G02X31791Y1152715I0J3203D01*
G01X31758Y1152755D01*
X31662Y1152792D01*
X31223Y1152733D01*
X31141Y1152671D01*
X31119Y1152624D01*
G02X28518Y1150023I-4741J2140D01*
G01X28471Y1150001D01*
X28409Y1149919D01*
X28350Y1149480D01*
X28387Y1149384D01*
X28427Y1149351D01*
G02X29580Y1146890I-2050J-2461D01*
G02X23176I-3202J0D01*
G02X24329Y1149351I3203J0D01*
G01X24369Y1149384D01*
X24406Y1149480D01*
X24347Y1149919D01*
X24285Y1150001D01*
X24238Y1150023D01*
G02Y1159505I2139J4741D01*
G01X24285Y1159527D01*
X24347Y1159609D01*
X24406Y1160048D01*
X24369Y1160144D01*
X24329Y1160177D01*
G02X23176Y1162638I2050J2461D01*
G02X29580I3202J0D01*
G02X29457Y1161758I-3202J-1D01*
G01X29442Y1161705D01*
X29469Y1161600D01*
X30859Y1160210D01*
G03X31000Y1160152I141J142D01*
G01X31316D01*
G03X31494Y1160260I0J200D01*
G01X31683Y1160626D01*
X31675Y1160737D01*
X31642Y1160783D01*
G02X31050Y1162638I2610J1855D01*
G02X32203Y1165099I3203J0D01*
G01X32243Y1165132D01*
X32280Y1165228D01*
X32221Y1165667D01*
X32159Y1165749D01*
X32112Y1165771D01*
G02X29511Y1168372I2140J4741D01*
G01X29489Y1168419D01*
X29407Y1168481D01*
X28968Y1168540D01*
X28872Y1168503D01*
X28839Y1168463D01*
G02X26378Y1167310I-2461J2050D01*
G02X23176Y1170512I0J3202D01*
G02X24329Y1172973I3203J0D01*
G01X24369Y1173006D01*
X24406Y1173102D01*
X24347Y1173541D01*
X24285Y1173623D01*
X24238Y1173645D01*
G02Y1183127I2139J4741D01*
G01X24285Y1183149D01*
X24347Y1183231D01*
G37*
G36*
G01X175134D02*
X175193Y1183670D01*
X175156Y1183766D01*
X175116Y1183799D01*
G02X173963Y1186260I2050J2461D01*
G02X180367I3202J0D01*
G02X179214Y1183799I-3203J0D01*
G01X179174Y1183766D01*
X179137Y1183670D01*
X179196Y1183231D01*
X179258Y1183149D01*
X179305Y1183127D01*
G02Y1173645I-2139J-4741D01*
G01X179258Y1173623D01*
X179196Y1173541D01*
X179137Y1173102D01*
X179174Y1173006D01*
X179214Y1172973D01*
G02X180367Y1170512I-2050J-2461D01*
G02X173963I-3202J0D01*
G02X174086Y1171392I3202J1D01*
G01X174101Y1171445D01*
X174074Y1171550D01*
X172734Y1172890D01*
G03X172593Y1172948I-141J-142D01*
G01X172262D01*
G03X172085Y1172842I-1J-200D01*
G01X171894Y1172479D01*
X171901Y1172368D01*
X171932Y1172322D01*
G02X172493Y1170512I-2641J-1810D01*
G02X171340Y1168051I-3203J0D01*
G01X171300Y1168018D01*
X171263Y1167922D01*
X171322Y1167483D01*
X171384Y1167401D01*
X171431Y1167379D01*
G02X174032Y1164778I-2140J-4741D01*
G01X174054Y1164731D01*
X174136Y1164669D01*
X174575Y1164610D01*
X174671Y1164647D01*
X174704Y1164687D01*
G02X177165Y1165840I2461J-2050D01*
G02X180367Y1162638I0J-3202D01*
G02X179214Y1160177I-3203J0D01*
G01X179174Y1160144D01*
X179137Y1160048D01*
X179196Y1159609D01*
X179258Y1159527D01*
X179305Y1159505D01*
G02Y1150023I-2139J-4741D01*
G01X179258Y1150001D01*
X179196Y1149919D01*
X179137Y1149480D01*
X179174Y1149384D01*
X179214Y1149351D01*
G02X180367Y1146890I-2050J-2461D01*
G02X173963I-3202J0D01*
G02X175116Y1149351I3203J0D01*
G01X175156Y1149384D01*
X175193Y1149480D01*
X175134Y1149919D01*
X175072Y1150001D01*
X175025Y1150023D01*
G02X172424Y1152624I2140J4741D01*
G01X172402Y1152671D01*
X172320Y1152733D01*
X171881Y1152792D01*
X171785Y1152755D01*
X171752Y1152715D01*
G02X169291Y1151562I-2461J2050D01*
G02X166089Y1154764I0J3202D01*
G02X167242Y1157225I3203J0D01*
G01X167282Y1157258D01*
X167319Y1157354D01*
X167260Y1157793D01*
X167198Y1157875D01*
X167151Y1157897D01*
G02Y1167379I2139J4741D01*
G01X167198Y1167401D01*
X167260Y1167483D01*
X167319Y1167922D01*
X167282Y1168018D01*
X167242Y1168051D01*
G02X166089Y1170512I2050J2461D01*
G01Y1170565D01*
X166090Y1170626D01*
X166024Y1170728D01*
X165626Y1170897D01*
G03X165407Y1170854I-78J-184D01*
G01X165300Y1170747D01*
X165287Y1170726D01*
G02X164000Y1169998I-1287J774D01*
G02X162498Y1171500I0J1502D01*
G02X163226Y1172787I1502J0D01*
G01X163247Y1172800D01*
X165874Y1175426D01*
G02X166535Y1175805I1027J-1025D01*
G01X166584Y1175818D01*
X166657Y1175886D01*
X166798Y1176296D01*
X166782Y1176396D01*
X166752Y1176436D01*
G02X166089Y1178386I2539J1951D01*
G02X169291Y1181588I3202J0D01*
G02X171752Y1180435I0J-3203D01*
G01X171785Y1180395D01*
X171881Y1180358D01*
X172320Y1180417D01*
X172402Y1180479D01*
X172424Y1180526D01*
G02X175025Y1183127I4741J-2140D01*
G01X175072Y1183149D01*
X175134Y1183231D01*
G37*
G36*
G01X6917Y1221082D02*
Y1221418D01*
X6892Y1221485D01*
X6868Y1221513D01*
G02X6498Y1222500I1131J987D01*
G02X9502I1502J0D01*
G02X9132Y1221513I-1501J0D01*
G01X9108Y1221485D01*
X9083Y1221418D01*
Y1221082D01*
X9108Y1221015D01*
X9132Y1220987D01*
G02X9502Y1220000I-1131J-987D01*
G02X6498I-1502J0D01*
G02X6868Y1220987I1501J0D01*
G01X6892Y1221015D01*
X6917Y1221082D01*
G37*
G36*
G01X194417D02*
Y1221418D01*
X194392Y1221485D01*
X194368Y1221513D01*
G02X193998Y1222500I1131J987D01*
G02X197002I1502J0D01*
G02X196632Y1221513I-1501J0D01*
G01X196608Y1221485D01*
X196583Y1221418D01*
Y1221082D01*
X196608Y1221015D01*
X196632Y1220987D01*
G02X197002Y1220000I-1131J-987D01*
G02X193998I-1502J0D01*
G02X194368Y1220987I1501J0D01*
G01X194392Y1221015D01*
X194417Y1221082D01*
G37*
G36*
G01X29423Y926822D02*
G02X29123Y928241I3202J1418D01*
G02X36127I3502J0D01*
G02X35827Y926822I-3502J-1D01*
G03Y926660I182J-81D01*
G02X36127Y925241I-3202J-1418D01*
G02X33823Y921950I-3502J0D01*
G01X33762Y921928D01*
X33690Y921822D01*
X33703Y921313D01*
X33781Y921211D01*
X33843Y921192D01*
G02X36327Y917841I-1018J-3351D01*
G02X36027Y916422I-3502J-1D01*
G03Y916260I182J-81D01*
G02X36327Y914841I-3202J-1418D01*
G02X29323I-3502J0D01*
G02X29623Y916260I3502J1D01*
G03Y916422I-182J81D01*
G02X29323Y917841I3202J1418D01*
G02X31627Y921132I3502J0D01*
G01X31688Y921154D01*
X31760Y921260D01*
X31747Y921769D01*
X31669Y921871D01*
X31607Y921890D01*
G02X29123Y925241I1018J3351D01*
G02X29423Y926660I3502J1D01*
G03Y926822I-182J81D01*
G37*
G36*
G01X139916Y976916D02*
G02X138605Y976147I-1311J733D01*
G02Y979151I0J1502D01*
G02X139975Y978264I0J-1502D01*
G03X140689Y978233I365J164D01*
G02X142000Y979002I1311J-733D01*
G02Y975998I0J-1502D01*
G02X140630Y976885I0J1502D01*
G03X139916Y976916I-365J-164D01*
G37*
G36*
G01X57461Y1006767D02*
G02X56150Y1005998I-1311J733D01*
G02Y1009002I0J1502D01*
G02X57301Y1008465I0J-1502D01*
G03X57957Y1008526I307J256D01*
G02X59268Y1009295I1311J-733D01*
G02Y1006291I0J-1502D01*
G02X58117Y1006828I0J1502D01*
G03X57461Y1006767I-307J-256D01*
G37*
G36*
G01X172381Y1024044D02*
G02X170929Y1022927I-1452J385D01*
G02Y1025931I0J1502D01*
G02X171790Y1025660I0J-1503D01*
G03X172406Y1025885I230J327D01*
G02X173858Y1027002I1452J-385D01*
G02Y1023998I0J-1502D01*
G02X172997Y1024269I0J1503D01*
G03X172381Y1024044I-230J-327D01*
G37*
G36*
G01X52247Y1024700D02*
X52226Y1024713D01*
G02X51498Y1026000I774J1287D01*
G02X53000Y1027502I1502J0D01*
G02X54287Y1026774I0J-1502D01*
G01X54300Y1026753D01*
X56526Y1024526D01*
G02X56952Y1023500I-1025J-1027D01*
G01Y1015897D01*
G02X56526Y1014871I-1451J1D01*
G01X53362Y1011706D01*
G03X53304Y1011565I142J-141D01*
G01Y1010216D01*
G02X52878Y1009190I-1451J1D01*
G01X49792Y1006103D01*
X49779Y1006082D01*
G02X48492Y1005354I-1287J774D01*
G02X46990Y1006856I0J1502D01*
G02X47718Y1008143I1502J0D01*
G01X47739Y1008156D01*
X50342Y1010759D01*
G03X50400Y1010900I-142J141D01*
G01Y1011862D01*
X50395Y1011886D01*
G02X50350Y1012249I1457J365D01*
G02X51078Y1013536I1502J0D01*
G01X51099Y1013549D01*
X53990Y1016440D01*
G03X54048Y1016581I-142J141D01*
G01Y1019712D01*
G03X53963Y1019876I-200J0D01*
G01X53655Y1020092D01*
X53558Y1020105D01*
X53512Y1020088D01*
G02X53000Y1019998I-512J1411D01*
G02X51499Y1021459I0J1502D01*
G01X51497Y1021514D01*
X51438Y1021607D01*
X51023Y1021815D01*
X50913Y1021806D01*
X50868Y1021774D01*
G02X50000Y1021498I-868J1227D01*
G02Y1024502I0J1502D01*
G02X51501Y1023041I0J-1502D01*
G01X51503Y1022986D01*
X51562Y1022893D01*
X51977Y1022685D01*
X52087Y1022694D01*
X52132Y1022726D01*
G02X52984Y1023002I868J-1226D01*
G01X53045Y1023003D01*
X53144Y1023070D01*
X53306Y1023468D01*
G03X53263Y1023685I-185J76D01*
G01X52247Y1024700D01*
G37*
G36*
G01X61524Y1047073D02*
G02X62725Y1047286I1203J-3289D01*
G02X63926Y1047073I-2J-3502D01*
G03X64064I69J188D01*
G02X65265Y1047286I1203J-3289D01*
G02X68767Y1043784I0J-3502D01*
G02X68561Y1042602I-3502J1D01*
G03Y1042466I189J-68D01*
G02X68767Y1041284I-3296J-1183D01*
G02X65265Y1037782I-3502J0D01*
G02X64083Y1037988I1J3502D01*
G03X63947I-68J-189D01*
G02X62765Y1037782I-1183J3296D01*
G02X61545Y1038001I-1J3502D01*
G03X61405I-70J-187D01*
G02X60185Y1037782I-1219J3283D01*
G02X57115Y1039599I0J3502D01*
G01X57086Y1039651D01*
X56981Y1039707D01*
X56497Y1039663D01*
X56404Y1039589D01*
X56385Y1039532D01*
G02X56357Y1039453I-3314J1130D01*
G03Y1039317I189J-68D01*
G02X56563Y1038135I-3296J-1183D01*
G02X53061Y1034633I-3502J0D01*
G02X51879Y1034839I1J3502D01*
G03X51743I-68J-189D01*
G02X50561Y1034633I-1183J3296D01*
G02X49341Y1034852I-1J3502D01*
G03X49201I-70J-187D01*
G02X47981Y1034633I-1219J3283D01*
G02X44479Y1038135I0J3502D01*
G02X44685Y1039317I3502J-1D01*
G03Y1039453I-189J68D01*
G02X44479Y1040635I3296J1183D01*
G02X47981Y1044137I3502J0D01*
G02X49182Y1043924I-2J-3502D01*
G03X49320I69J188D01*
G02X50521Y1044137I1203J-3289D01*
G02X51722Y1043924I-2J-3502D01*
G03X51860I69J188D01*
G02X53061Y1044137I1203J-3289D01*
G02X56131Y1042320I0J-3502D01*
G01X56160Y1042268D01*
X56265Y1042212D01*
X56749Y1042256D01*
X56842Y1042330D01*
X56861Y1042387D01*
G02X56889Y1042466I3314J-1130D01*
G03Y1042602I-189J68D01*
G02X56683Y1043784I3296J1183D01*
G02X60185Y1047286I3502J0D01*
G02X61386Y1047073I-2J-3502D01*
G03X61524I69J188D01*
G37*
G36*
G01X170321D02*
G02X171522Y1047286I1203J-3289D01*
G02X172723Y1047073I-2J-3502D01*
G03X172861I69J188D01*
G02X174062Y1047286I1203J-3289D01*
G02X177564Y1043784I0J-3502D01*
G02X177358Y1042602I-3502J1D01*
G03Y1042466I189J-68D01*
G02X177564Y1041284I-3296J-1183D01*
G02X174062Y1037782I-3502J0D01*
G02X172880Y1037988I1J3502D01*
G03X172744I-68J-189D01*
G02X171562Y1037782I-1183J3296D01*
G02X170342Y1038001I-1J3502D01*
G03X170202I-70J-187D01*
G02X168982Y1037782I-1219J3283D01*
G02X165912Y1039599I0J3502D01*
G01X165883Y1039651D01*
X165778Y1039707D01*
X165294Y1039663D01*
X165201Y1039589D01*
X165182Y1039532D01*
G02X165154Y1039453I-3314J1130D01*
G03Y1039317I189J-68D01*
G02X165360Y1038135I-3296J-1183D01*
G02X161858Y1034633I-3502J0D01*
G02X160676Y1034839I1J3502D01*
G03X160540I-68J-189D01*
G02X159358Y1034633I-1183J3296D01*
G02X158138Y1034852I-1J3502D01*
G03X157998I-70J-187D01*
G02X156778Y1034633I-1219J3283D01*
G02X153276Y1038135I0J3502D01*
G02X153482Y1039317I3502J-1D01*
G03Y1039453I-189J68D01*
G02X153276Y1040635I3296J1183D01*
G02X156778Y1044137I3502J0D01*
G02X157979Y1043924I-2J-3502D01*
G03X158117I69J188D01*
G02X159318Y1044137I1203J-3289D01*
G02X160519Y1043924I-2J-3502D01*
G03X160657I69J188D01*
G02X161858Y1044137I1203J-3289D01*
G02X164928Y1042320I0J-3502D01*
G01X164957Y1042268D01*
X165062Y1042212D01*
X165546Y1042256D01*
X165639Y1042330D01*
X165658Y1042387D01*
G02X165686Y1042466I3314J-1130D01*
G03Y1042602I-189J68D01*
G02X165480Y1043784I3296J1183D01*
G02X168982Y1047286I3502J0D01*
G02X170183Y1047073I-2J-3502D01*
G03X170321I69J188D01*
G37*
G36*
G01X75052Y1063057D02*
G02X74358Y1064323I808J1266D01*
G02X77362I1502J0D01*
G02X76694Y1063074I-1502J0D01*
G03X76701Y1062404I222J-333D01*
G02X77395Y1061138I-808J-1266D01*
G02X74391I-1502J0D01*
G02X75059Y1062387I1502J0D01*
G03X75052Y1063057I-222J333D01*
G37*
G36*
G01X125952Y1069757D02*
G02X125258Y1071023I808J1266D01*
G02X128262I1502J0D01*
G02X127594Y1069774I-1502J0D01*
G03X127601Y1069104I222J-333D01*
G02X128295Y1067838I-808J-1266D01*
G02X125291I-1502J0D01*
G02X125959Y1069087I1502J0D01*
G03X125952Y1069757I-222J333D01*
G37*
G36*
G01X75816Y1077825D02*
X75767Y1077850D01*
G02X74962Y1079181I698J1331D01*
G02X77966I1502J0D01*
G02X77210Y1077877I-1503J0D01*
G01X77161Y1077850D01*
X77108Y1077755D01*
X77117Y1077294D01*
X77174Y1077201D01*
X77223Y1077176D01*
G02X78028Y1075845I-698J-1331D01*
G02X77474Y1074680I-1502J0D01*
G01X77439Y1074652D01*
X77401Y1074574D01*
X77393Y1074180D01*
X77428Y1074100D01*
X77461Y1074070D01*
G02X77966Y1072947I-996J-1123D01*
G02X77210Y1071643I-1503J0D01*
G01X77161Y1071616D01*
X77108Y1071521D01*
X77117Y1071060D01*
X77174Y1070967D01*
X77223Y1070942D01*
G02X78028Y1069611I-698J-1331D01*
G02X75024I-1502J0D01*
G02X75780Y1070915I1503J0D01*
G01X75829Y1070942D01*
X75882Y1071037D01*
X75873Y1071498D01*
X75816Y1071591D01*
X75767Y1071616D01*
G02X74962Y1072947I698J1331D01*
G02X75516Y1074112I1502J0D01*
G01X75551Y1074140D01*
X75589Y1074218D01*
X75597Y1074612D01*
X75562Y1074692D01*
X75529Y1074722D01*
G02X75024Y1075845I996J1123D01*
G02X75780Y1077149I1503J0D01*
G01X75829Y1077176D01*
X75882Y1077271D01*
X75873Y1077732D01*
X75816Y1077825D01*
G37*
G36*
G01X75734Y1093234D02*
G02X74929Y1094565I698J1331D01*
G02X77933I1502J0D01*
G02X77177Y1093261I-1503J0D01*
G03X77190Y1092560I199J-347D01*
G02X77995Y1091229I-698J-1331D01*
G02X74991I-1502J0D01*
G02X75747Y1092533I1503J0D01*
G03X75734Y1093234I-199J347D01*
G37*
G36*
G01X31789Y1136969D02*
X31749Y1137019D01*
G02X31050Y1139016I2503J1997D01*
G02X34252Y1135814I3202J0D01*
G02X34023Y1135822I-3J3202D01*
G01X33959Y1135827D01*
X33851Y1135762D01*
X33648Y1135300D01*
X33673Y1135177D01*
X33719Y1135133D01*
G02X26911I-3404J-3597D01*
G01X26957Y1135177D01*
X26982Y1135300D01*
X26779Y1135762D01*
X26671Y1135827D01*
X26607Y1135822D01*
G02X26378Y1135814I-226J3194D01*
G02X29580Y1139016I0J3202D01*
G02X28881Y1137019I-3202J0D01*
G01X28841Y1136969D01*
X28833Y1136843D01*
X29099Y1136414D01*
X29215Y1136365D01*
X29277Y1136378D01*
G02X31353I1038J-4842D01*
G01X31415Y1136365D01*
X31531Y1136414D01*
X31797Y1136843D01*
X31789Y1136969D01*
G37*
G36*
G01X135059Y1195999D02*
G02X135000Y1195998I-55J1501D01*
G02X136502Y1197500I0J1502D01*
G02X136363Y1196869I-1502J0D01*
G03X136741Y1196301I363J-168D01*
G02X136800Y1196302I55J-1501D01*
G02X135298Y1194800I0J-1502D01*
G02X135437Y1195431I1502J0D01*
G03X135059Y1195999I-363J168D01*
G37*
G36*
G01X169870Y1197973D02*
X169824Y1198017D01*
G02X176632I3404J3597D01*
G01X176586Y1197973D01*
X176561Y1197850D01*
X176764Y1197388D01*
X176872Y1197323D01*
X176936Y1197328D01*
G02X177165Y1197336I226J-3194D01*
G02X173963Y1194134I0J-3202D01*
G02X174662Y1196131I3202J0D01*
G01X174702Y1196181D01*
X174710Y1196307D01*
X174444Y1196736D01*
X174328Y1196785D01*
X174266Y1196772D01*
G02X172190I-1038J4842D01*
G01X172128Y1196785D01*
X172012Y1196736D01*
X171746Y1196307D01*
X171754Y1196181D01*
X171794Y1196131D01*
G02X172493Y1194134I-2503J-1997D01*
G02X169291Y1197336I-3202J0D01*
G02X169520Y1197328I3J-3202D01*
G01X169584Y1197323D01*
X169692Y1197388D01*
X169895Y1197850D01*
X169870Y1197973D01*
G37*
G36*
G01X60629Y801539D02*
G02X62058Y802577I1429J-465D01*
G02X63560Y801075I0J-1502D01*
G02X63057Y799953I-1503J0D01*
G03X63017Y799702I133J-150D01*
G02X63502Y797925I-3017J-1778D01*
G02X60000Y801427I-3502J0D01*
G02X60416Y801402I-2J-3502D01*
G03X60629Y801539I23J199D01*
G37*
G36*
G01X69890Y801472D02*
G02X69983Y800951I-1409J-520D01*
G02X66979I-1502J0D01*
G02X66985Y801090I1502J5D01*
G03X66852Y801298I-199J19D01*
G02X64498Y804606I1147J3308D01*
G02X71502I3502J0D01*
G02X69965Y801707I-3502J0D01*
G03X69890Y801472I112J-165D01*
G37*
G54D19*
X141890Y246451D03*
X173858Y298500D03*
X155482Y266228D03*
X11874Y154893D03*
X18000Y491500D03*
X40500Y295500D03*
X136500Y261000D03*
X10000Y267303D03*
X172905Y279728D03*
X169358Y286228D03*
X64500Y287000D03*
X147500Y278228D03*
X38383Y280119D03*
X161200Y251200D03*
X159430Y244830D03*
X17953Y267500D03*
X21500D03*
X25545Y248578D03*
X9400Y241516D03*
X183500Y299500D03*
X170358Y298858D03*
X35484Y534075D03*
X29500Y512500D03*
Y520500D03*
X20452Y513547D03*
X27580Y528341D03*
X137495Y248875D03*
X22170Y246150D03*
X42309Y251270D03*
X61300Y66900D03*
X68416Y63842D03*
X69100Y76100D03*
X75173Y78000D03*
X71650Y94259D03*
X94430Y103830D03*
X91059Y94630D03*
X112500Y76000D03*
X135500Y70441D03*
X142727Y79842D03*
X142000Y74575D03*
X87500Y83300D03*
X94730Y1173910D03*
X61000Y1172500D03*
X74313Y1178559D03*
X135500Y1143441D03*
X132350Y1156741D03*
X126500Y1129000D03*
X112941Y1146240D03*
X121000Y1128425D03*
X142500Y1183500D03*
X125000Y1198000D03*
X69018Y1147650D03*
X73505Y1200075D03*
X77816Y1128650D03*
X192500Y1215000D03*
X72000Y1013500D03*
X66000Y1025000D03*
X64108Y1006500D03*
X160732Y977966D03*
X42000Y1023000D03*
X11000Y1215000D03*
X44100Y1027850D03*
X48005Y1012038D03*
X40500Y995000D03*
X139435Y996649D03*
X62500Y1025500D03*
X35259Y968798D03*
X38500Y977199D03*
X149500Y1023000D03*
X159000Y972500D03*
X153150Y1028430D03*
X26500Y997500D03*
X74000Y1026000D03*
X68686Y1139993D03*
X138650Y1149500D03*
X135800Y1138000D03*
X64843Y1194000D03*
X64850Y1179000D03*
X129112Y978769D03*
X182058Y1022519D03*
X138650Y1165500D03*
X11000Y1239500D03*
X182741Y1235150D03*
X56000Y1203273D03*
X10241Y1234150D03*
X182600Y1228850D03*
X192000Y1240500D03*
X19500Y1239500D03*
X183500Y1240500D03*
X12150Y1227850D03*
X23500Y1237000D03*
X45240Y657000D03*
Y669500D03*
Y682000D03*
X46950Y666500D03*
Y672500D03*
X25023Y663850D03*
Y669850D03*
X15012Y745563D03*
X47499Y649000D03*
X60000Y696984D03*
X77018Y836764D03*
X71650Y821000D03*
X62216Y830875D03*
X58673Y775800D03*
X60773Y820614D03*
X69018Y783764D03*
X61000Y810000D03*
X65350Y818654D03*
X61576Y762200D03*
X66000Y776000D03*
X67993Y827764D03*
X58612Y740500D03*
X126500Y706500D03*
X114857Y741500D03*
X119000Y734000D03*
X142727Y791500D03*
X171500Y743500D03*
X171580Y716500D03*
X139650Y785905D03*
X171586Y735683D03*
X171440Y708767D03*
X171977Y656850D03*
G54D20*
X123500Y59500D03*
X80500Y74000D03*
X165500Y1229900D03*
X76400Y1188100D03*
X123000Y1181000D03*
G54D18*
X34252Y467362D03*
X26378D03*
X34252Y459488D03*
Y103976D03*
X26378D03*
X34252Y96102D03*
X169291Y48858D03*
X177165D03*
X169291Y56732D03*
X34252Y1194134D03*
X26378D03*
X34252Y1186260D03*
X169291Y1139016D03*
X177165D03*
X169291Y1146890D03*
G54D21*
X101772Y1287047D03*
G54D17*
X44000Y17500D03*
X178500D03*
X20000Y1307000D03*
%LPD*%
G75*
G54D10*
X-63431Y1152816D03*
X-53431D03*
G54D11*
X3005Y30675D03*
Y50675D03*
Y70675D03*
Y90675D03*
Y110675D03*
Y130675D03*
Y150675D03*
Y170675D03*
Y190675D03*
Y210675D03*
Y230675D03*
Y250675D03*
Y270675D03*
X10500Y274500D03*
X11800Y284000D03*
X3005Y290675D03*
Y310675D03*
Y330675D03*
Y350675D03*
Y370675D03*
Y390675D03*
Y410675D03*
Y430675D03*
Y450675D03*
Y470675D03*
Y490675D03*
Y510675D03*
Y530675D03*
Y550675D03*
Y570675D03*
Y590675D03*
Y610675D03*
X12000Y641000D03*
X3005Y630675D03*
Y650675D03*
Y670675D03*
Y690675D03*
Y710675D03*
Y730675D03*
Y750675D03*
Y770675D03*
Y790675D03*
Y810675D03*
Y830675D03*
Y850675D03*
Y870675D03*
Y890675D03*
Y910675D03*
Y930675D03*
Y950675D03*
Y970675D03*
X9838Y994729D03*
X3005Y990675D03*
Y1010675D03*
Y1030675D03*
Y1050675D03*
Y1070675D03*
Y1090675D03*
Y1110675D03*
Y1130675D03*
Y1150675D03*
Y1170675D03*
Y1190675D03*
Y1210675D03*
Y1230675D03*
Y1250675D03*
Y1270675D03*
Y1290675D03*
Y1310675D03*
X15868Y3010D03*
X26040Y245190D03*
X12791Y261000D03*
X32716Y273500D03*
X24000Y276000D03*
X29500Y534075D03*
X28900Y556900D03*
X32258Y646000D03*
X21000Y644000D03*
X32760Y657000D03*
X21525Y660000D03*
Y654000D03*
X12389Y653509D03*
X12512Y647013D03*
X14925Y663000D03*
X21525Y666500D03*
X32760Y669500D03*
X21525Y672500D03*
X32760Y682000D03*
X12500Y679000D03*
X14925Y669000D03*
Y690000D03*
X13000Y709000D03*
X20453Y708047D03*
X15713Y710009D03*
X20327Y711174D03*
X17500Y734000D03*
Y741000D03*
Y748000D03*
X12819Y751500D03*
X12419Y765261D03*
X14830Y763614D03*
X23000Y760000D03*
X13500Y862500D03*
X26990Y975034D03*
X23702Y992261D03*
X30522Y1000288D03*
X15000Y1001300D03*
X16017Y1323770D03*
X34927Y3006D03*
X54927D03*
X38880Y263169D03*
X44500Y272767D03*
X40472Y283287D03*
X55650Y280728D03*
X53343Y301334D03*
X49689Y474203D03*
X56925Y503000D03*
Y528500D03*
Y508500D03*
Y523500D03*
Y518500D03*
X57000Y538500D03*
X56475Y654000D03*
Y672500D03*
X34000Y757000D03*
X37000Y756900D03*
X38900Y800200D03*
X52800Y813500D03*
X47813Y833013D03*
X40972Y1010059D03*
X38880Y989941D03*
X48492Y1006856D03*
X51852Y1012249D03*
X53000Y1026000D03*
X40500Y1164000D03*
X35517Y1323770D03*
X56017D03*
X61802Y25927D03*
X68508Y50969D03*
X60475Y79692D03*
X61000Y84192D03*
X68500Y70000D03*
X71500Y130000D03*
X72500Y283771D03*
X66561Y273985D03*
X78500Y406000D03*
X60475Y424728D03*
Y429228D03*
X71000Y427000D03*
X58500Y454500D03*
X79500Y449925D03*
X58500Y441000D03*
X70500Y443500D03*
X57000Y483000D03*
X56925Y498000D03*
Y493000D03*
Y488000D03*
Y513500D03*
Y533500D03*
X72500Y541500D03*
X75396Y544500D03*
X56475Y641000D03*
X78457Y634010D03*
X78677Y637315D03*
X56475Y647000D03*
Y660000D03*
X68000Y664000D03*
X56475Y666500D03*
Y679000D03*
Y685000D03*
X69000Y669745D03*
X68000Y676500D03*
X59475Y688975D03*
X61500Y728500D03*
X74075Y721500D03*
Y726500D03*
X76725Y749500D03*
X69000Y771500D03*
X71500Y805500D03*
X77000Y819000D03*
X73000Y1010500D03*
X69802Y1006198D03*
X64231Y1115268D03*
X77518Y1138500D03*
X76500Y1162975D03*
X60475Y1152000D03*
X61500Y1160000D03*
X79000Y1157425D03*
Y1173425D03*
X79106Y1176575D03*
X75000Y1196500D03*
X76017Y1323770D03*
X82975Y53333D03*
X84400Y64200D03*
X99000Y61000D03*
X99883Y57500D03*
X79500Y86925D03*
X88802Y100198D03*
X86000Y92000D03*
X79500Y104425D03*
X82500Y398000D03*
X79463Y429962D03*
X91500Y434000D03*
X100835Y446500D03*
X91593Y439000D03*
X95184Y493787D03*
X102075Y534000D03*
X85000Y562148D03*
X97000Y569153D03*
X90680Y561766D03*
X99051Y635051D03*
X87500Y634700D03*
X88300Y639800D03*
X91532Y663261D03*
X95032Y660000D03*
X101284Y671500D03*
X101309Y675500D03*
X79975Y739975D03*
X99279Y781942D03*
X99500Y787000D03*
X83000Y804000D03*
X94000Y818500D03*
X101500Y824271D03*
X83000Y810000D03*
X104500Y834500D03*
X91000Y1173425D03*
X81000Y1193425D03*
X86000Y1176575D03*
X96017Y1323770D03*
X118475Y83500D03*
X115918Y75650D03*
X112000Y88700D03*
X123500Y115500D03*
X107000Y400425D03*
X118500Y403500D03*
X110500Y445000D03*
X106850Y441596D03*
X109000Y485000D03*
X108500Y512000D03*
X125000Y562500D03*
X106977Y561919D03*
X121500Y557500D03*
X108601Y627084D03*
X118079Y639954D03*
X106000Y634500D03*
X117500Y689900D03*
X118000Y696000D03*
X115525Y731000D03*
Y745000D03*
Y738000D03*
X121536Y749253D03*
X121841Y775967D03*
X119836Y761664D03*
X125654Y772281D03*
X118711Y797500D03*
X120500Y845000D03*
X119500Y992000D03*
X110000Y1128425D03*
X121000Y1131575D03*
X124500Y1148575D03*
X118000Y1151575D03*
X116017Y1323770D03*
X146740Y3016D03*
X141748Y26922D03*
X135014Y50977D03*
X127000Y77500D03*
X132350Y94273D03*
X142500Y103342D03*
X142000Y98842D03*
X137449Y113340D03*
X133529Y265385D03*
X147393Y265728D03*
X142400Y269800D03*
X136482Y272471D03*
X132850Y421837D03*
X130500Y432500D03*
X129000Y468000D03*
X148000Y483000D03*
X150575Y504500D03*
X141500Y516500D03*
X150575Y534500D03*
X135500Y562500D03*
X133491Y560490D03*
X131500Y634500D03*
X135000Y637500D03*
X150300Y645900D03*
X141900Y645410D03*
X128000Y694500D03*
X133575Y692000D03*
X139150Y712500D03*
X136500Y728500D03*
X128065Y725566D03*
X136500Y742000D03*
X129285Y781799D03*
X128500Y791500D03*
X132370Y788872D03*
X128500Y786500D03*
X138428Y806903D03*
X141088Y804709D03*
X133246Y811300D03*
X142999Y842350D03*
X148281Y838882D03*
X145600Y838100D03*
X146000Y854500D03*
X133529Y995306D03*
X136482Y1002392D03*
X147393Y995649D03*
X147229Y1004299D03*
X132175Y1117325D03*
X127000Y1143000D03*
Y1157025D03*
Y1166000D03*
X142500Y1161500D03*
X126360Y1185947D03*
X142500Y1176000D03*
X136017Y1323770D03*
X165799Y3002D03*
X150500Y247000D03*
X161105Y266081D03*
X149769Y283287D03*
X164947Y280728D03*
X160777Y275688D03*
X162783Y301463D03*
X151635Y476202D03*
X154000Y471000D03*
X150575Y494500D03*
Y499500D03*
X150500Y489500D03*
X150575Y524500D03*
Y519500D03*
Y509500D03*
X150500Y544500D03*
X150575Y539500D03*
Y529500D03*
X169475Y706000D03*
Y733000D03*
Y713000D03*
Y720000D03*
X163925Y756500D03*
X169475Y747000D03*
Y740000D03*
X149000Y854500D03*
X149658Y974968D03*
X161581Y995673D03*
X149769Y1010059D03*
X164947Y1007500D03*
X164337Y1002475D03*
X161884Y1026048D03*
X164000Y1171500D03*
X156017Y1323770D03*
X185799Y3002D03*
X178811Y281071D03*
X175858Y273985D03*
X189250Y541750D03*
X191991Y536336D03*
X194000Y550000D03*
X191259Y547500D03*
X182500Y641600D03*
X187500Y643500D03*
X176000Y659500D03*
X175500Y651500D03*
X180500Y684500D03*
X182500Y688000D03*
X177500Y679500D03*
X175500Y672500D03*
X175475Y668500D03*
X179000Y676500D03*
X187925Y701000D03*
X181000Y696500D03*
X179000Y694000D03*
X190300Y725200D03*
X187041Y730000D03*
X193000Y754500D03*
X191000Y756500D03*
X184425Y738000D03*
X189000Y758500D03*
X173200Y770800D03*
X178811Y1007843D03*
X175858Y1000757D03*
X176017Y1323770D03*
X194471Y1321882D03*
X199120Y9903D03*
X200536Y29059D03*
Y49059D03*
Y69059D03*
Y109059D03*
Y89059D03*
Y129059D03*
Y149059D03*
Y169059D03*
Y189059D03*
Y209059D03*
Y249059D03*
Y229059D03*
Y269059D03*
Y289059D03*
Y309059D03*
Y329059D03*
Y349059D03*
Y369059D03*
Y409059D03*
Y389059D03*
Y429059D03*
Y449059D03*
Y469059D03*
Y489059D03*
Y509059D03*
Y549059D03*
Y529059D03*
Y569059D03*
Y589059D03*
Y609059D03*
Y629059D03*
Y649059D03*
Y669059D03*
Y709059D03*
Y689059D03*
Y729059D03*
X195000Y752500D03*
X200536Y749059D03*
Y769059D03*
Y789059D03*
Y809059D03*
Y849059D03*
Y829059D03*
Y869059D03*
Y889059D03*
Y909059D03*
Y929059D03*
Y947059D03*
Y969059D03*
Y1009059D03*
Y989059D03*
Y1029059D03*
Y1049059D03*
Y1069059D03*
Y1089059D03*
Y1109059D03*
Y1149059D03*
Y1129059D03*
Y1169059D03*
Y1189059D03*
Y1209059D03*
Y1229059D03*
Y1249059D03*
Y1289059D03*
Y1269059D03*
Y1309059D03*
G54D12*
X34252Y56732D03*
Y420118D03*
Y783504D03*
X26378Y791378D03*
X34252Y1146890D03*
X26378Y1162638D03*
X169291Y96102D03*
Y459488D03*
Y822874D03*
Y1186260D03*
X177165Y815000D03*
Y1170512D03*
G54D13*
G01X36628Y795328D02*
X30328D01*
G54D14*
G01X13500Y862500D02*
Y769500D01*
X23000Y760000D01*
G01X38900Y800200D02*
Y797600D01*
X36628Y795328D01*
G01X30328D02*
X26378Y791378D01*
G01X82500Y398000D02*
X82073Y397573D01*
X79526D01*
X72453Y404646D01*
Y425547D01*
X71000Y427000D01*
G01X70500Y443500D02*
X70000Y443000D01*
Y428000D01*
X71000Y427000D01*
G01X110500Y445000D02*
X109400Y443900D01*
Y440399D01*
X107587Y438586D01*
Y412744D01*
X112026Y408305D01*
Y402951D01*
X109500Y400425D01*
X107000D01*
G01X173200Y770800D02*
X179500D01*
X183350Y774650D01*
Y808815D01*
X177165Y815000D01*
G54D15*
G01X-320500Y-470483D02*
Y2626000D01*
X2967000D01*
Y-470483D01*
X-320500D01*
G01X329322Y-314459D02*
Y-319459D01*
G01X327865Y-314459D02*
X330779D01*
G01X335689Y-319459D02*
X333155D01*
Y-314459D01*
X335689D01*
G01X334675Y-316876D02*
X333155D01*
G01X338255Y-314459D02*
Y-319459D01*
X340789D01*
G01X344622Y-319626D02*
X344495Y-319542D01*
Y-319376D01*
X344622Y-319292D01*
X344749Y-319376D01*
Y-319542D01*
X344622Y-319626D01*
G01Y-317376D02*
X344495Y-317292D01*
Y-317126D01*
X344622Y-317042D01*
X344749Y-317126D01*
Y-317292D01*
X344622Y-317376D01*
G01X349405Y-321126D02*
X348772Y-320292D01*
X348455Y-319459D01*
Y-316126D01*
X348772Y-315292D01*
X349405Y-314459D01*
G01X354822D02*
X354315Y-314626D01*
X353935Y-315042D01*
X353682Y-315542D01*
X353492Y-316209D01*
X353429Y-316959D01*
X353492Y-317709D01*
X353682Y-318376D01*
X353935Y-318876D01*
X354315Y-319292D01*
X354822Y-319459D01*
X355329Y-319292D01*
X355709Y-318876D01*
X355962Y-318376D01*
X356152Y-317709D01*
X356215Y-316959D01*
X356152Y-316209D01*
X355962Y-315542D01*
X355709Y-315042D01*
X355329Y-314626D01*
X354822Y-314459D01*
G01X358529Y-318459D02*
X358909Y-319042D01*
X359415Y-319376D01*
X359985Y-319459D01*
X360492Y-319376D01*
X360999Y-318959D01*
X361315Y-318459D01*
X361379Y-317959D01*
X361252Y-317376D01*
X360809Y-316959D01*
X360365Y-316792D01*
X359795D01*
G01X360365D02*
X360745Y-316542D01*
X361062Y-316126D01*
X361189Y-315626D01*
X361062Y-315126D01*
X360745Y-314709D01*
X360175Y-314459D01*
X359605Y-314542D01*
X359035Y-314876D01*
G01X365339Y-321126D02*
X365972Y-320292D01*
X366289Y-319459D01*
Y-316126D01*
X365972Y-315292D01*
X365339Y-314459D01*
G01X368729Y-318459D02*
X369109Y-319042D01*
X369615Y-319376D01*
X370185Y-319459D01*
X370692Y-319376D01*
X371199Y-318959D01*
X371515Y-318459D01*
X371579Y-317959D01*
X371452Y-317376D01*
X371009Y-316959D01*
X370565Y-316792D01*
X369995D01*
G01X370565D02*
X370945Y-316542D01*
X371262Y-316126D01*
X371389Y-315626D01*
X371262Y-315126D01*
X370945Y-314709D01*
X370375Y-314459D01*
X369805Y-314542D01*
X369235Y-314876D01*
G01X374019Y-315292D02*
X374399Y-314792D01*
X374842Y-314542D01*
X375349Y-314459D01*
X375982Y-314626D01*
X376425Y-315042D01*
X376552Y-315542D01*
X376489Y-316042D01*
X376235Y-316459D01*
X374969Y-317292D01*
X374399Y-317876D01*
X374019Y-318709D01*
X373892Y-319459D01*
X376552D01*
G01X380195D02*
X380322Y-318376D01*
X380512Y-317459D01*
X380765Y-316626D01*
X381082Y-315709D01*
X381589Y-314459D01*
X379055D01*
G01X384599Y-317792D02*
X386245D01*
G01X389319Y-315292D02*
X389699Y-314792D01*
X390142Y-314542D01*
X390649Y-314459D01*
X391282Y-314626D01*
X391725Y-315042D01*
X391852Y-315542D01*
X391789Y-316042D01*
X391535Y-316459D01*
X390269Y-317292D01*
X389699Y-317876D01*
X389319Y-318709D01*
X389192Y-319459D01*
X391852D01*
G01X394229Y-318459D02*
X394609Y-319042D01*
X395115Y-319376D01*
X395685Y-319459D01*
X396192Y-319376D01*
X396699Y-318959D01*
X397015Y-318459D01*
X397079Y-317959D01*
X396952Y-317376D01*
X396509Y-316959D01*
X396065Y-316792D01*
X395495D01*
G01X396065D02*
X396445Y-316542D01*
X396762Y-316126D01*
X396889Y-315626D01*
X396762Y-315126D01*
X396445Y-314709D01*
X395875Y-314459D01*
X395305Y-314542D01*
X394735Y-314876D01*
G01X401482Y-319459D02*
Y-314459D01*
X399139Y-318042D01*
X402305D01*
G01X404429Y-318709D02*
X404809Y-319126D01*
X405252Y-319376D01*
X405822Y-319459D01*
X406392Y-319292D01*
X406835Y-318959D01*
X407152Y-318376D01*
X407215Y-317709D01*
X407089Y-317042D01*
X406772Y-316626D01*
X406329Y-316292D01*
X405885Y-316209D01*
X405442Y-316292D01*
X404872Y-316626D01*
X405062Y-314459D01*
X406772D01*
G01X414819Y-319459D02*
Y-314459D01*
X417225D01*
G01X416339Y-316876D02*
X414819D01*
G01X419539Y-319459D02*
X421122Y-314459D01*
X422705Y-319459D01*
G01X422135Y-317709D02*
X420109D01*
G01X424892Y-319459D02*
X427552Y-314459D01*
G01X424892D02*
X427552Y-319459D01*
G01X431322Y-319626D02*
X431195Y-319542D01*
Y-319376D01*
X431322Y-319292D01*
X431449Y-319376D01*
Y-319542D01*
X431322Y-319626D01*
G01Y-317376D02*
X431195Y-317292D01*
Y-317126D01*
X431322Y-317042D01*
X431449Y-317126D01*
Y-317292D01*
X431322Y-317376D01*
G01X436105Y-321126D02*
X435472Y-320292D01*
X435155Y-319459D01*
Y-316126D01*
X435472Y-315292D01*
X436105Y-314459D01*
G01X441522D02*
X441015Y-314626D01*
X440635Y-315042D01*
X440382Y-315542D01*
X440192Y-316209D01*
X440129Y-316959D01*
X440192Y-317709D01*
X440382Y-318376D01*
X440635Y-318876D01*
X441015Y-319292D01*
X441522Y-319459D01*
X442029Y-319292D01*
X442409Y-318876D01*
X442662Y-318376D01*
X442852Y-317709D01*
X442915Y-316959D01*
X442852Y-316209D01*
X442662Y-315542D01*
X442409Y-315042D01*
X442029Y-314626D01*
X441522Y-314459D01*
G01X445229Y-318459D02*
X445609Y-319042D01*
X446115Y-319376D01*
X446685Y-319459D01*
X447192Y-319376D01*
X447699Y-318959D01*
X448015Y-318459D01*
X448079Y-317959D01*
X447952Y-317376D01*
X447509Y-316959D01*
X447065Y-316792D01*
X446495D01*
G01X447065D02*
X447445Y-316542D01*
X447762Y-316126D01*
X447889Y-315626D01*
X447762Y-315126D01*
X447445Y-314709D01*
X446875Y-314459D01*
X446305Y-314542D01*
X445735Y-314876D01*
G01X452039Y-321126D02*
X452672Y-320292D01*
X452989Y-319459D01*
Y-316126D01*
X452672Y-315292D01*
X452039Y-314459D01*
G01X455429Y-318459D02*
X455809Y-319042D01*
X456315Y-319376D01*
X456885Y-319459D01*
X457392Y-319376D01*
X457899Y-318959D01*
X458215Y-318459D01*
X458279Y-317959D01*
X458152Y-317376D01*
X457709Y-316959D01*
X457265Y-316792D01*
X456695D01*
G01X457265D02*
X457645Y-316542D01*
X457962Y-316126D01*
X458089Y-315626D01*
X457962Y-315126D01*
X457645Y-314709D01*
X457075Y-314459D01*
X456505Y-314542D01*
X455935Y-314876D01*
G01X460845Y-318876D02*
X461289Y-319292D01*
X461795Y-319459D01*
X462302Y-319292D01*
X462745Y-318792D01*
X463062Y-318042D01*
X463189Y-317292D01*
Y-316376D01*
X463062Y-315626D01*
X462745Y-314959D01*
X462365Y-314626D01*
X461922Y-314459D01*
X461415Y-314626D01*
X461035Y-314959D01*
X460782Y-315459D01*
X460655Y-316126D01*
X460782Y-316709D01*
X461099Y-317292D01*
X461479Y-317626D01*
X461922Y-317709D01*
X462429Y-317542D01*
X462809Y-317126D01*
X463189Y-316376D01*
G01X466895Y-319459D02*
X467022Y-318376D01*
X467212Y-317459D01*
X467465Y-316626D01*
X467782Y-315709D01*
X468289Y-314459D01*
X465755D01*
G01X471299Y-317792D02*
X472945D01*
G01X475829Y-318459D02*
X476209Y-319042D01*
X476715Y-319376D01*
X477285Y-319459D01*
X477792Y-319376D01*
X478299Y-318959D01*
X478615Y-318459D01*
X478679Y-317959D01*
X478552Y-317376D01*
X478109Y-316959D01*
X477665Y-316792D01*
X477095D01*
G01X477665D02*
X478045Y-316542D01*
X478362Y-316126D01*
X478489Y-315626D01*
X478362Y-315126D01*
X478045Y-314709D01*
X477475Y-314459D01*
X476905Y-314542D01*
X476335Y-314876D01*
G01X481119Y-317376D02*
X481562Y-316792D01*
X481942Y-316459D01*
X482449Y-316292D01*
X482892Y-316459D01*
X483209Y-316792D01*
X483462Y-317292D01*
X483525Y-317876D01*
X483462Y-318376D01*
X483209Y-318876D01*
X482829Y-319292D01*
X482385Y-319459D01*
X481879Y-319292D01*
X481435Y-318792D01*
X481182Y-318042D01*
X481119Y-317209D01*
X481245Y-316126D01*
X481435Y-315542D01*
X481752Y-314959D01*
X482195Y-314542D01*
X482639Y-314459D01*
X483082Y-314626D01*
X483399Y-315042D01*
G01X487422Y-319459D02*
Y-314459D01*
X486662Y-315459D01*
G01Y-319459D02*
X488182D01*
G01X493282D02*
Y-314459D01*
X490939Y-318042D01*
X494105D01*
G01X317322Y-249459D02*
Y-324459D01*
X817322D01*
Y-249459D01*
X317322D01*
G01X512322D02*
Y-324459D01*
G01Y-299459D02*
X615322D01*
Y-274459D01*
G01X512322D02*
X615322D01*
G01X622829Y-309459D02*
Y-304459D01*
X624095D01*
X624602Y-304709D01*
X624982Y-305042D01*
X625299Y-305542D01*
X625552Y-306126D01*
X625615Y-306959D01*
X625552Y-307792D01*
X625299Y-308376D01*
X624982Y-308876D01*
X624602Y-309209D01*
X624095Y-309459D01*
X622829D01*
G01X627739D02*
X629322Y-304459D01*
X630905Y-309459D01*
G01X630335Y-307709D02*
X628309D01*
G01X634422Y-304459D02*
Y-309459D01*
G01X632965Y-304459D02*
X635879D01*
G01X640789Y-309459D02*
X638255D01*
Y-304459D01*
X640789D01*
G01X639775Y-306876D02*
X638255D01*
G01X644622Y-309626D02*
X644495Y-309542D01*
Y-309376D01*
X644622Y-309292D01*
X644749Y-309376D01*
Y-309542D01*
X644622Y-309626D01*
G01Y-307376D02*
X644495Y-307292D01*
Y-307126D01*
X644622Y-307042D01*
X644749Y-307126D01*
Y-307292D01*
X644622Y-307376D01*
G01X617322Y-249459D02*
Y-324459D01*
G01X615322Y-249459D02*
Y-324459D01*
G01X622955Y-284459D02*
Y-279459D01*
X624475D01*
X624982Y-279709D01*
X625362Y-280292D01*
X625489Y-280959D01*
X625362Y-281626D01*
X625045Y-282126D01*
X624475Y-282376D01*
X622955D01*
G01X628182Y-284626D02*
X630462Y-279459D01*
G01X632965Y-284459D02*
Y-279459D01*
X635879Y-284459D01*
Y-279459D01*
G01X639522Y-284626D02*
X639395Y-284542D01*
Y-284376D01*
X639522Y-284292D01*
X639649Y-284376D01*
Y-284542D01*
X639522Y-284626D01*
G01Y-282376D02*
X639395Y-282292D01*
Y-282126D01*
X639522Y-282042D01*
X639649Y-282126D01*
Y-282292D01*
X639522Y-282376D01*
G01X617322Y-299459D02*
X817322D01*
G01X622955Y-259459D02*
Y-254459D01*
X624475D01*
X624982Y-254709D01*
X625362Y-255292D01*
X625489Y-255959D01*
X625362Y-256626D01*
X625045Y-257126D01*
X624475Y-257376D01*
X622955D01*
G01X628055Y-259459D02*
Y-254459D01*
X629639D01*
X630145Y-254709D01*
X630462Y-255042D01*
X630589Y-255709D01*
X630462Y-256376D01*
X630082Y-256792D01*
X629639Y-257042D01*
X628055D01*
G01X629639D02*
X630589Y-259459D01*
G01X634422D02*
X633915Y-259376D01*
X633472Y-259042D01*
X633092Y-258542D01*
X632839Y-257959D01*
X632712Y-257292D01*
Y-256626D01*
X632839Y-255959D01*
X633092Y-255376D01*
X633472Y-254876D01*
X633915Y-254542D01*
X634422Y-254459D01*
X634929Y-254542D01*
X635372Y-254876D01*
X635752Y-255376D01*
X636005Y-255959D01*
X636132Y-256626D01*
Y-257292D01*
X636005Y-257959D01*
X635752Y-258542D01*
X635372Y-259042D01*
X634929Y-259376D01*
X634422Y-259459D01*
G01X638255Y-258459D02*
X638572Y-258959D01*
X638952Y-259292D01*
X639395Y-259459D01*
X639902Y-259292D01*
X640282Y-258959D01*
X640662Y-258459D01*
X640789Y-257792D01*
Y-254459D01*
G01X645889Y-259459D02*
X643355D01*
Y-254459D01*
X645889D01*
G01X644875Y-256876D02*
X643355D01*
G01X651115Y-254876D02*
X650735Y-254626D01*
X650292Y-254459D01*
X649785D01*
X649215Y-254709D01*
X648772Y-255126D01*
X648455Y-255626D01*
X648202Y-256459D01*
X648139Y-257209D01*
X648265Y-257959D01*
X648455Y-258459D01*
X648835Y-258959D01*
X649279Y-259292D01*
X649722Y-259459D01*
X650165D01*
X650609Y-259292D01*
X650989Y-259042D01*
X651305Y-258709D01*
G01X654822Y-254459D02*
Y-259459D01*
G01X653365Y-254459D02*
X656279D01*
G01X659922Y-259626D02*
X659795Y-259542D01*
Y-259376D01*
X659922Y-259292D01*
X660049Y-259376D01*
Y-259542D01*
X659922Y-259626D01*
G01Y-257376D02*
X659795Y-257292D01*
Y-257126D01*
X659922Y-257042D01*
X660049Y-257126D01*
Y-257292D01*
X659922Y-257376D01*
G01X617322Y-274459D02*
X817322D01*
G01X734955Y-301959D02*
Y-306959D01*
X737489D01*
G01X740562Y-301959D02*
X742082D01*
G01X741322D02*
Y-306959D01*
G01X740562D02*
X742082D01*
G01X746929Y-304292D02*
X747182Y-304042D01*
X747372Y-303626D01*
X747499Y-303042D01*
X747372Y-302542D01*
X747119Y-302209D01*
X746675Y-301959D01*
X744965D01*
Y-306959D01*
X747055D01*
X747499Y-306626D01*
X747752Y-306126D01*
X747879Y-305542D01*
X747752Y-304959D01*
X747372Y-304459D01*
X746929Y-304292D01*
X744965D01*
G01X751522Y-307126D02*
X751395Y-307042D01*
Y-306876D01*
X751522Y-306792D01*
X751649Y-306876D01*
Y-307042D01*
X751522Y-307126D01*
G01Y-304876D02*
X751395Y-304792D01*
Y-304626D01*
X751522Y-304542D01*
X751649Y-304626D01*
Y-304792D01*
X751522Y-304876D01*
G01X732322Y-299459D02*
Y-324459D01*
G01X779222Y-301959D02*
Y-306959D01*
G01X777765Y-301959D02*
X780679D01*
G01X784322Y-306959D02*
X783942Y-306876D01*
X783562Y-306542D01*
X783309Y-305959D01*
X783182Y-305292D01*
X783309Y-304626D01*
X783562Y-304042D01*
X783942Y-303709D01*
X784322Y-303626D01*
X784702Y-303709D01*
X785082Y-304042D01*
X785335Y-304626D01*
X785399Y-305292D01*
X785335Y-305959D01*
X785082Y-306542D01*
X784702Y-306876D01*
X784322Y-306959D01*
G01X789422D02*
X789042Y-306876D01*
X788662Y-306542D01*
X788409Y-305959D01*
X788282Y-305292D01*
X788409Y-304626D01*
X788662Y-304042D01*
X789042Y-303709D01*
X789422Y-303626D01*
X789802Y-303709D01*
X790182Y-304042D01*
X790435Y-304626D01*
X790499Y-305292D01*
X790435Y-305959D01*
X790182Y-306542D01*
X789802Y-306876D01*
X789422Y-306959D01*
G01X794522D02*
Y-301959D01*
G01X799622Y-307126D02*
X799495Y-307042D01*
Y-306876D01*
X799622Y-306792D01*
X799749Y-306876D01*
Y-307042D01*
X799622Y-307126D01*
G01Y-304876D02*
X799495Y-304792D01*
Y-304626D01*
X799622Y-304542D01*
X799749Y-304626D01*
Y-304792D01*
X799622Y-304876D01*
G01X775322Y-299459D02*
Y-324459D01*
G01Y-274459D02*
Y-299459D01*
G01X777955Y-281959D02*
Y-276959D01*
X779539D01*
X780045Y-277209D01*
X780362Y-277542D01*
X780489Y-278209D01*
X780362Y-278876D01*
X779982Y-279292D01*
X779539Y-279542D01*
X777955D01*
G01X779539D02*
X780489Y-281959D01*
G01X785589D02*
X783055D01*
Y-276959D01*
X785589D01*
G01X784575Y-279376D02*
X783055D01*
G01X787839Y-276959D02*
X789422Y-281959D01*
X791005Y-276959D01*
G01X794522Y-282126D02*
X794395Y-282042D01*
Y-281876D01*
X794522Y-281792D01*
X794649Y-281876D01*
Y-282042D01*
X794522Y-282126D01*
G01Y-279876D02*
X794395Y-279792D01*
Y-279626D01*
X794522Y-279542D01*
X794649Y-279626D01*
Y-279792D01*
X794522Y-279876D01*
G01X798082Y-326159D02*
X798162Y-326084D01*
X798222Y-325959D01*
X798262Y-325784D01*
X798222Y-325634D01*
X798142Y-325534D01*
X798002Y-325459D01*
X797462D01*
Y-326959D01*
X798122D01*
X798262Y-326859D01*
X798342Y-326709D01*
X798382Y-326534D01*
X798342Y-326359D01*
X798222Y-326209D01*
X798082Y-326159D01*
X797462D01*
G01X799482Y-326959D02*
Y-325959D01*
G01Y-326134D02*
X799402Y-326034D01*
X799282Y-325984D01*
X799142Y-325959D01*
X799002Y-326009D01*
X798882Y-326109D01*
X798802Y-326259D01*
X798762Y-326459D01*
X798802Y-326659D01*
X798882Y-326809D01*
X799002Y-326909D01*
X799142Y-326959D01*
X799282Y-326934D01*
X799402Y-326859D01*
X799482Y-326759D01*
G01X800022Y-326784D02*
X800122Y-326884D01*
X800262Y-326959D01*
X800382D01*
X800502Y-326909D01*
X800582Y-326834D01*
X800622Y-326734D01*
X800602Y-326584D01*
X800522Y-326509D01*
X800162Y-326359D01*
X800082Y-326184D01*
X800122Y-326059D01*
X800202Y-325984D01*
X800322Y-325959D01*
X800442Y-325984D01*
X800562Y-326059D01*
G01X801222Y-326284D02*
X801862D01*
X801802Y-326109D01*
X801702Y-326009D01*
X801562Y-325959D01*
X801422Y-325984D01*
X801302Y-326059D01*
X801222Y-326234D01*
X801182Y-326384D01*
Y-326534D01*
X801222Y-326684D01*
X801322Y-326834D01*
X801442Y-326934D01*
X801582Y-326959D01*
X801722Y-326909D01*
X801862Y-326759D01*
G01X802362Y-326959D02*
Y-325459D01*
G01Y-326209D02*
X802462Y-326059D01*
X802582Y-325984D01*
X802702Y-325959D01*
X802882Y-326009D01*
X803002Y-326109D01*
X803082Y-326284D01*
Y-326484D01*
X803042Y-326684D01*
X802962Y-326834D01*
X802822Y-326934D01*
X802702Y-326959D01*
X802582Y-326934D01*
X802462Y-326859D01*
X802362Y-326734D01*
G01X803922Y-326959D02*
X803802Y-326934D01*
X803682Y-326834D01*
X803602Y-326659D01*
X803562Y-326459D01*
X803602Y-326259D01*
X803682Y-326084D01*
X803802Y-325984D01*
X803922Y-325959D01*
X804042Y-325984D01*
X804162Y-326084D01*
X804242Y-326259D01*
X804262Y-326459D01*
X804242Y-326659D01*
X804162Y-326834D01*
X804042Y-326934D01*
X803922Y-326959D01*
G01X805482D02*
Y-325959D01*
G01Y-326134D02*
X805402Y-326034D01*
X805282Y-325984D01*
X805142Y-325959D01*
X805002Y-326009D01*
X804882Y-326109D01*
X804802Y-326259D01*
X804762Y-326459D01*
X804802Y-326659D01*
X804882Y-326809D01*
X805002Y-326909D01*
X805142Y-326959D01*
X805282Y-326934D01*
X805402Y-326859D01*
X805482Y-326759D01*
G01X806042Y-326959D02*
Y-325959D01*
G01Y-326159D02*
X806142Y-326059D01*
X806242Y-325984D01*
X806382Y-325959D01*
X806482Y-325984D01*
X806602Y-326059D01*
G01X807882Y-325459D02*
Y-326959D01*
G01Y-326734D02*
X807802Y-326859D01*
X807682Y-326934D01*
X807542Y-326959D01*
X807382Y-326909D01*
X807262Y-326784D01*
X807182Y-326634D01*
X807162Y-326459D01*
X807182Y-326284D01*
X807262Y-326134D01*
X807382Y-326009D01*
X807542Y-325959D01*
X807682Y-325984D01*
X807782Y-326034D01*
X807882Y-326134D01*
G01X809522Y-326959D02*
Y-325459D01*
X810022D01*
X810182Y-325534D01*
X810282Y-325634D01*
X810322Y-325834D01*
X810282Y-326034D01*
X810162Y-326159D01*
X810022Y-326234D01*
X809522D01*
G01X810022D02*
X810322Y-326959D01*
G01X810822Y-326284D02*
X811462D01*
X811402Y-326109D01*
X811302Y-326009D01*
X811162Y-325959D01*
X811022Y-325984D01*
X810902Y-326059D01*
X810822Y-326234D01*
X810782Y-326384D01*
Y-326534D01*
X810822Y-326684D01*
X810922Y-326834D01*
X811042Y-326934D01*
X811182Y-326959D01*
X811322Y-326909D01*
X811462Y-326759D01*
G01X811962Y-325959D02*
X812322Y-326959D01*
X812682Y-325959D01*
G01X813522Y-327009D02*
X813482Y-326984D01*
Y-326934D01*
X813522Y-326909D01*
X813562Y-326934D01*
Y-326984D01*
X813522Y-327009D01*
G01X814682Y-326959D02*
X814722Y-326634D01*
X814782Y-326359D01*
X814862Y-326109D01*
X814962Y-325834D01*
X815122Y-325459D01*
X814322D01*
G01X816082Y-326159D02*
X816162Y-326084D01*
X816222Y-325959D01*
X816262Y-325784D01*
X816222Y-325634D01*
X816142Y-325534D01*
X816002Y-325459D01*
X815462D01*
Y-326959D01*
X816122D01*
X816262Y-326859D01*
X816342Y-326709D01*
X816382Y-326534D01*
X816342Y-326359D01*
X816222Y-326209D01*
X816082Y-326159D01*
X815462D01*
G01X-320500Y-470483D02*
Y2626000D01*
X2967000D01*
Y-470483D01*
X-320500D01*
G01X331395Y-304184D02*
X330925Y-303869D01*
X330377Y-303659D01*
X329750D01*
X329045Y-303974D01*
X328497Y-304499D01*
X328105Y-305129D01*
X327792Y-306179D01*
X327714Y-307124D01*
X327870Y-308069D01*
X328105Y-308699D01*
X328575Y-309329D01*
X329124Y-309749D01*
X329672Y-309959D01*
X330220D01*
X330769Y-309749D01*
X331239Y-309434D01*
X331630Y-309014D01*
G01X335032Y-303659D02*
X336912D01*
G01X335972D02*
Y-309959D01*
G01X335032D02*
X336912D01*
G01X342272Y-303659D02*
Y-309959D01*
G01X340470Y-303659D02*
X344074D01*
G01X348572Y-309959D02*
Y-307124D01*
X347005Y-303659D01*
G01X350139D02*
X348572Y-307124D01*
G01X359449Y-308699D02*
X359919Y-309434D01*
X360545Y-309854D01*
X361250Y-309959D01*
X361877Y-309854D01*
X362504Y-309329D01*
X362895Y-308699D01*
X362974Y-308069D01*
X362817Y-307334D01*
X362269Y-306809D01*
X361720Y-306599D01*
X361015D01*
G01X361720D02*
X362190Y-306284D01*
X362582Y-305759D01*
X362739Y-305129D01*
X362582Y-304499D01*
X362190Y-303974D01*
X361485Y-303659D01*
X360780Y-303764D01*
X360075Y-304184D01*
G01X365749Y-308699D02*
X366219Y-309434D01*
X366845Y-309854D01*
X367550Y-309959D01*
X368177Y-309854D01*
X368804Y-309329D01*
X369195Y-308699D01*
X369274Y-308069D01*
X369117Y-307334D01*
X368569Y-306809D01*
X368020Y-306599D01*
X367315D01*
G01X368020D02*
X368490Y-306284D01*
X368882Y-305759D01*
X369039Y-305129D01*
X368882Y-304499D01*
X368490Y-303974D01*
X367785Y-303659D01*
X367080Y-303764D01*
X366375Y-304184D01*
G01X372049Y-308699D02*
X372519Y-309434D01*
X373145Y-309854D01*
X373850Y-309959D01*
X374477Y-309854D01*
X375104Y-309329D01*
X375495Y-308699D01*
X375574Y-308069D01*
X375417Y-307334D01*
X374869Y-306809D01*
X374320Y-306599D01*
X373615D01*
G01X374320D02*
X374790Y-306284D01*
X375182Y-305759D01*
X375339Y-305129D01*
X375182Y-304499D01*
X374790Y-303974D01*
X374085Y-303659D01*
X373380Y-303764D01*
X372675Y-304184D01*
G01X379915Y-309959D02*
X380072Y-308594D01*
X380307Y-307439D01*
X380620Y-306389D01*
X381012Y-305234D01*
X381639Y-303659D01*
X378505D01*
G01X386215Y-309959D02*
X386372Y-308594D01*
X386607Y-307439D01*
X386920Y-306389D01*
X387312Y-305234D01*
X387939Y-303659D01*
X384805D01*
G01X392515Y-311114D02*
X392829Y-309749D01*
G01X398972Y-303659D02*
Y-309959D01*
G01X397170Y-303659D02*
X400774D01*
G01X403314Y-309959D02*
X405272Y-303659D01*
X407230Y-309959D01*
G01X406525Y-307754D02*
X404019D01*
G01X410632Y-303659D02*
X412512D01*
G01X411572D02*
Y-309959D01*
G01X410632D02*
X412512D01*
G01X415522Y-303659D02*
X416619Y-309959D01*
X417872Y-303659D01*
X419125Y-309959D01*
X420222Y-303659D01*
G01X422214Y-309959D02*
X424172Y-303659D01*
X426130Y-309959D01*
G01X425425Y-307754D02*
X422919D01*
G01X428670Y-309959D02*
Y-303659D01*
X432274Y-309959D01*
Y-303659D01*
G01X442680Y-312059D02*
X441897Y-311009D01*
X441505Y-309959D01*
Y-305759D01*
X441897Y-304709D01*
X442680Y-303659D01*
G01X454105Y-309959D02*
Y-303659D01*
X456064D01*
X456690Y-303974D01*
X457082Y-304394D01*
X457239Y-305234D01*
X457082Y-306074D01*
X456612Y-306599D01*
X456064Y-306914D01*
X454105D01*
G01X456064D02*
X457239Y-309959D01*
G01X461972Y-310169D02*
X461815Y-310064D01*
Y-309854D01*
X461972Y-309749D01*
X462129Y-309854D01*
Y-310064D01*
X461972Y-310169D01*
G01X468272Y-309959D02*
X467645Y-309854D01*
X467097Y-309434D01*
X466627Y-308804D01*
X466314Y-308069D01*
X466157Y-307229D01*
Y-306389D01*
X466314Y-305549D01*
X466627Y-304814D01*
X467097Y-304184D01*
X467645Y-303764D01*
X468272Y-303659D01*
X468899Y-303764D01*
X469447Y-304184D01*
X469917Y-304814D01*
X470230Y-305549D01*
X470387Y-306389D01*
Y-307229D01*
X470230Y-308069D01*
X469917Y-308804D01*
X469447Y-309434D01*
X468899Y-309854D01*
X468272Y-309959D01*
G01X474572Y-310169D02*
X474415Y-310064D01*
Y-309854D01*
X474572Y-309749D01*
X474729Y-309854D01*
Y-310064D01*
X474572Y-310169D01*
G01X482595Y-304184D02*
X482125Y-303869D01*
X481577Y-303659D01*
X480950D01*
X480245Y-303974D01*
X479697Y-304499D01*
X479305Y-305129D01*
X478992Y-306179D01*
X478914Y-307124D01*
X479070Y-308069D01*
X479305Y-308699D01*
X479775Y-309329D01*
X480324Y-309749D01*
X480872Y-309959D01*
X481420D01*
X481969Y-309749D01*
X482439Y-309434D01*
X482830Y-309014D01*
G01X487172Y-310169D02*
X487015Y-310064D01*
Y-309854D01*
X487172Y-309749D01*
X487329Y-309854D01*
Y-310064D01*
X487172Y-310169D01*
G01X493864Y-312059D02*
X494647Y-311009D01*
X495039Y-309959D01*
Y-305759D01*
X494647Y-304709D01*
X493864Y-303659D01*
G01X330142Y-296809D02*
X331709D01*
Y-298699D01*
X331239Y-299329D01*
X330690Y-299749D01*
X329907Y-299959D01*
X329124Y-299749D01*
X328575Y-299329D01*
X328105Y-298699D01*
X327792Y-297964D01*
X327635Y-297124D01*
Y-296389D01*
X327792Y-295759D01*
X328105Y-295024D01*
X328575Y-294394D01*
X329045Y-293974D01*
X329672Y-293659D01*
X330220D01*
X330847Y-293869D01*
X331317Y-294289D01*
G01X334249Y-293659D02*
Y-298174D01*
X334562Y-299119D01*
X335189Y-299749D01*
X335972Y-299959D01*
X336755Y-299749D01*
X337382Y-299119D01*
X337695Y-298174D01*
Y-293659D01*
G01X341332D02*
X343212D01*
G01X342272D02*
Y-299959D01*
G01X341332D02*
X343212D01*
G01X346927Y-299119D02*
X347554Y-299644D01*
X348259Y-299959D01*
X348885D01*
X349512Y-299644D01*
X349982Y-299119D01*
X350217Y-298384D01*
X350060Y-297649D01*
X349669Y-297019D01*
X348964Y-296599D01*
X348024Y-296389D01*
X347475Y-295969D01*
X347240Y-295234D01*
X347397Y-294499D01*
X347789Y-293974D01*
X348337Y-293659D01*
X348885D01*
X349434Y-293869D01*
X349904Y-294394D01*
G01X353227Y-299959D02*
Y-293659D01*
G01X356517D02*
Y-299959D01*
G01Y-296809D02*
X353227D01*
G01X359214Y-299959D02*
X361172Y-293659D01*
X363130Y-299959D01*
G01X362425Y-297754D02*
X359919D01*
G01X365670Y-299959D02*
Y-293659D01*
X369274Y-299959D01*
Y-293659D01*
G01X378349Y-299959D02*
Y-293659D01*
X379915D01*
X380542Y-293974D01*
X381012Y-294394D01*
X381404Y-295024D01*
X381717Y-295759D01*
X381795Y-296809D01*
X381717Y-297859D01*
X381404Y-298594D01*
X381012Y-299224D01*
X380542Y-299644D01*
X379915Y-299959D01*
X378349D01*
G01X385432Y-293659D02*
X387312D01*
G01X386372D02*
Y-299959D01*
G01X385432D02*
X387312D01*
G01X391027Y-299119D02*
X391654Y-299644D01*
X392359Y-299959D01*
X392985D01*
X393612Y-299644D01*
X394082Y-299119D01*
X394317Y-298384D01*
X394160Y-297649D01*
X393769Y-297019D01*
X393064Y-296599D01*
X392124Y-296389D01*
X391575Y-295969D01*
X391340Y-295234D01*
X391497Y-294499D01*
X391889Y-293974D01*
X392437Y-293659D01*
X392985D01*
X393534Y-293869D01*
X394004Y-294394D01*
G01X398972Y-293659D02*
Y-299959D01*
G01X397170Y-293659D02*
X400774D01*
G01X405272Y-300169D02*
X405115Y-300064D01*
Y-299854D01*
X405272Y-299749D01*
X405429Y-299854D01*
Y-300064D01*
X405272Y-300169D01*
G01X411415Y-301114D02*
X411729Y-299749D01*
G01X417872Y-293659D02*
Y-299959D01*
G01X416070Y-293659D02*
X419674D01*
G01X422214Y-299959D02*
X424172Y-293659D01*
X426130Y-299959D01*
G01X425425Y-297754D02*
X422919D01*
G01X430472Y-299959D02*
X429845Y-299854D01*
X429297Y-299434D01*
X428827Y-298804D01*
X428514Y-298069D01*
X428357Y-297229D01*
Y-296389D01*
X428514Y-295549D01*
X428827Y-294814D01*
X429297Y-294184D01*
X429845Y-293764D01*
X430472Y-293659D01*
X431099Y-293764D01*
X431647Y-294184D01*
X432117Y-294814D01*
X432430Y-295549D01*
X432587Y-296389D01*
Y-297229D01*
X432430Y-298069D01*
X432117Y-298804D01*
X431647Y-299434D01*
X431099Y-299854D01*
X430472Y-299959D01*
G01X436772D02*
Y-297124D01*
X435205Y-293659D01*
G01X438339D02*
X436772Y-297124D01*
G01X441349Y-293659D02*
Y-298174D01*
X441662Y-299119D01*
X442289Y-299749D01*
X443072Y-299959D01*
X443855Y-299749D01*
X444482Y-299119D01*
X444795Y-298174D01*
Y-293659D01*
G01X447414Y-299959D02*
X449372Y-293659D01*
X451330Y-299959D01*
G01X450625Y-297754D02*
X448119D01*
G01X453870Y-299959D02*
Y-293659D01*
X457474Y-299959D01*
Y-293659D01*
G01X327870Y-289959D02*
Y-283659D01*
X331474Y-289959D01*
Y-283659D01*
G01X335972Y-289959D02*
X335345Y-289854D01*
X334797Y-289434D01*
X334327Y-288804D01*
X334014Y-288069D01*
X333857Y-287229D01*
Y-286389D01*
X334014Y-285549D01*
X334327Y-284814D01*
X334797Y-284184D01*
X335345Y-283764D01*
X335972Y-283659D01*
X336599Y-283764D01*
X337147Y-284184D01*
X337617Y-284814D01*
X337930Y-285549D01*
X338087Y-286389D01*
Y-287229D01*
X337930Y-288069D01*
X337617Y-288804D01*
X337147Y-289434D01*
X336599Y-289854D01*
X335972Y-289959D01*
G01X342272Y-290169D02*
X342115Y-290064D01*
Y-289854D01*
X342272Y-289749D01*
X342429Y-289854D01*
Y-290064D01*
X342272Y-290169D01*
G01X347084Y-284709D02*
X347554Y-284079D01*
X348102Y-283764D01*
X348729Y-283659D01*
X349512Y-283869D01*
X350060Y-284394D01*
X350217Y-285024D01*
X350139Y-285654D01*
X349825Y-286179D01*
X348259Y-287229D01*
X347554Y-287964D01*
X347084Y-289014D01*
X346927Y-289959D01*
X350217D01*
G01X354872D02*
Y-283659D01*
X353932Y-284919D01*
G01Y-289959D02*
X355812D01*
G01X361172D02*
Y-283659D01*
X360232Y-284919D01*
G01Y-289959D02*
X362112D01*
G01X367315Y-291114D02*
X367629Y-289749D01*
G01X371422Y-283659D02*
X372519Y-289959D01*
X373772Y-283659D01*
X375025Y-289959D01*
X376122Y-283659D01*
G01X381639Y-289959D02*
X378505D01*
Y-283659D01*
X381639D01*
G01X380385Y-286704D02*
X378505D01*
G01X384570Y-289959D02*
Y-283659D01*
X388174Y-289959D01*
Y-283659D01*
G01X391027Y-289959D02*
Y-283659D01*
G01X394317D02*
Y-289959D01*
G01Y-286809D02*
X391027D01*
G01X397249Y-283659D02*
Y-288174D01*
X397562Y-289119D01*
X398189Y-289749D01*
X398972Y-289959D01*
X399755Y-289749D01*
X400382Y-289119D01*
X400695Y-288174D01*
Y-283659D01*
G01X403314Y-289959D02*
X405272Y-283659D01*
X407230Y-289959D01*
G01X406525Y-287754D02*
X404019D01*
G01X416384Y-284709D02*
X416854Y-284079D01*
X417402Y-283764D01*
X418029Y-283659D01*
X418812Y-283869D01*
X419360Y-284394D01*
X419517Y-285024D01*
X419439Y-285654D01*
X419125Y-286179D01*
X417559Y-287229D01*
X416854Y-287964D01*
X416384Y-289014D01*
X416227Y-289959D01*
X419517D01*
G01X422370D02*
Y-283659D01*
X425974Y-289959D01*
Y-283659D01*
G01X428749Y-289959D02*
Y-283659D01*
X430315D01*
X430942Y-283974D01*
X431412Y-284394D01*
X431804Y-285024D01*
X432117Y-285759D01*
X432195Y-286809D01*
X432117Y-287859D01*
X431804Y-288594D01*
X431412Y-289224D01*
X430942Y-289644D01*
X430315Y-289959D01*
X428749D01*
G01X441505D02*
Y-283659D01*
X443464D01*
X444090Y-283974D01*
X444482Y-284394D01*
X444639Y-285234D01*
X444482Y-286074D01*
X444012Y-286599D01*
X443464Y-286914D01*
X441505D01*
G01X443464D02*
X444639Y-289959D01*
G01X447649D02*
Y-283659D01*
X449215D01*
X449842Y-283974D01*
X450312Y-284394D01*
X450704Y-285024D01*
X451017Y-285759D01*
X451095Y-286809D01*
X451017Y-287859D01*
X450704Y-288594D01*
X450312Y-289224D01*
X449842Y-289644D01*
X449215Y-289959D01*
X447649D01*
G01X455672Y-290169D02*
X455515Y-290064D01*
Y-289854D01*
X455672Y-289749D01*
X455829Y-289854D01*
Y-290064D01*
X455672Y-290169D01*
G01X351972Y-279259D02*
X349452Y-278842D01*
X347247Y-277176D01*
X345357Y-274676D01*
X344097Y-271759D01*
X343467Y-268426D01*
Y-265092D01*
X344097Y-261759D01*
X345357Y-258842D01*
X347247Y-256343D01*
X349452Y-254676D01*
X351972Y-254259D01*
X354492Y-254676D01*
X356697Y-256343D01*
X358587Y-258842D01*
X359847Y-261759D01*
X360477Y-265092D01*
Y-268426D01*
X359847Y-271759D01*
X358587Y-274676D01*
X356697Y-277176D01*
X354492Y-278842D01*
X351972Y-279259D01*
G01X354492Y-272592D02*
X358272Y-279259D01*
G01X371817Y-262593D02*
Y-274259D01*
X373077Y-277176D01*
X374967Y-278842D01*
X377172Y-279259D01*
X379377Y-278842D01*
X381267Y-277176D01*
X382527Y-274259D01*
G01Y-279259D02*
Y-262593D01*
G01X408042Y-279259D02*
Y-262593D01*
G01Y-265509D02*
X406782Y-263843D01*
X404892Y-263009D01*
X402687Y-262593D01*
X400482Y-263426D01*
X398592Y-265092D01*
X397332Y-267593D01*
X396702Y-270926D01*
X397332Y-274259D01*
X398592Y-276760D01*
X400482Y-278426D01*
X402687Y-279259D01*
X404892Y-278842D01*
X406782Y-277593D01*
X408042Y-275926D01*
G01X422217Y-279259D02*
Y-262593D01*
G01Y-266759D02*
X423477Y-264676D01*
X425367Y-263009D01*
X427887Y-262593D01*
X430092Y-263009D01*
X431982Y-264676D01*
X432927Y-267593D01*
Y-279259D01*
G01X452772Y-254259D02*
Y-279259D01*
G01X448362Y-262593D02*
X457182D01*
G01X483642Y-279259D02*
Y-262593D01*
G01Y-265509D02*
X482382Y-263843D01*
X480492Y-263009D01*
X478287Y-262593D01*
X476082Y-263426D01*
X474192Y-265092D01*
X472932Y-267593D01*
X472302Y-270926D01*
X472932Y-274259D01*
X474192Y-276760D01*
X476082Y-278426D01*
X478287Y-279259D01*
X480492Y-278842D01*
X482382Y-277593D01*
X483642Y-275926D01*
G01X523322Y-258959D02*
Y-266959D01*
X527322D01*
G01X535122D02*
Y-261626D01*
G01Y-262559D02*
X534722Y-262026D01*
X534122Y-261759D01*
X533422Y-261626D01*
X532722Y-261892D01*
X532122Y-262426D01*
X531722Y-263226D01*
X531522Y-264292D01*
X531722Y-265359D01*
X532122Y-266159D01*
X532722Y-266692D01*
X533422Y-266959D01*
X534122Y-266826D01*
X534722Y-266426D01*
X535122Y-265893D01*
G01X539222Y-269359D02*
X539822Y-269626D01*
X540622Y-269359D01*
X541122Y-268826D01*
X541522Y-268159D01*
X542122Y-266026D01*
X543422Y-261626D01*
G01X540222D02*
X542122Y-266026D01*
G01X547822Y-263359D02*
X551022D01*
X550722Y-262426D01*
X550222Y-261892D01*
X549522Y-261626D01*
X548822Y-261759D01*
X548222Y-262159D01*
X547822Y-263092D01*
X547622Y-263893D01*
Y-264692D01*
X547822Y-265492D01*
X548322Y-266292D01*
X548922Y-266826D01*
X549622Y-266959D01*
X550322Y-266692D01*
X551022Y-265893D01*
G01X555922Y-266959D02*
Y-261626D01*
G01Y-262692D02*
X556422Y-262159D01*
X556922Y-261759D01*
X557622Y-261626D01*
X558122Y-261759D01*
X558722Y-262159D01*
G01X542022Y-316959D02*
Y-308959D01*
X546622Y-316959D01*
Y-308959D01*
G01X552322Y-311626D02*
Y-316959D01*
G01Y-309492D02*
X552122Y-309359D01*
Y-309092D01*
X552322Y-308959D01*
X552522Y-309092D01*
Y-309359D01*
X552322Y-309492D01*
G01X558622Y-316959D02*
Y-311626D01*
G01Y-312959D02*
X559022Y-312292D01*
X559622Y-311759D01*
X560422Y-311626D01*
X561122Y-311759D01*
X561722Y-312292D01*
X562022Y-313226D01*
Y-316959D01*
G01X570122D02*
Y-311626D01*
G01Y-312559D02*
X569722Y-312026D01*
X569122Y-311759D01*
X568422Y-311626D01*
X567722Y-311892D01*
X567122Y-312426D01*
X566722Y-313226D01*
X566522Y-314292D01*
X566722Y-315359D01*
X567122Y-316159D01*
X567722Y-316692D01*
X568422Y-316959D01*
X569122Y-316826D01*
X569722Y-316426D01*
X570122Y-315893D01*
G01X553122Y-283959D02*
X555522D01*
G01X554322D02*
Y-291959D01*
G01X553122D02*
X555522D01*
G01X560022D02*
Y-283959D01*
X564622Y-291959D01*
Y-283959D01*
G01X570322Y-291959D02*
Y-283959D01*
X569122Y-285559D01*
G01Y-291959D02*
X571522D01*
G01X574622Y-265359D02*
X575222Y-266292D01*
X576022Y-266826D01*
X576922Y-266959D01*
X577722Y-266826D01*
X578522Y-266159D01*
X579022Y-265359D01*
X579122Y-264559D01*
X578922Y-263626D01*
X578222Y-262959D01*
X577522Y-262692D01*
X576622D01*
G01X577522D02*
X578122Y-262292D01*
X578622Y-261626D01*
X578822Y-260826D01*
X578622Y-260026D01*
X578122Y-259359D01*
X577222Y-258959D01*
X576322Y-259092D01*
X575422Y-259626D01*
G01X649922Y-310292D02*
X650522Y-309492D01*
X651222Y-309092D01*
X652022Y-308959D01*
X653022Y-309226D01*
X653722Y-309892D01*
X653922Y-310692D01*
X653822Y-311493D01*
X653422Y-312159D01*
X651422Y-313492D01*
X650522Y-314426D01*
X649922Y-315759D01*
X649722Y-316959D01*
X653922D01*
G01X659822Y-308959D02*
X659022Y-309226D01*
X658422Y-309892D01*
X658022Y-310692D01*
X657722Y-311759D01*
X657622Y-312959D01*
X657722Y-314159D01*
X658022Y-315226D01*
X658422Y-316026D01*
X659022Y-316692D01*
X659822Y-316959D01*
X660622Y-316692D01*
X661222Y-316026D01*
X661622Y-315226D01*
X661922Y-314159D01*
X662022Y-312959D01*
X661922Y-311759D01*
X661622Y-310692D01*
X661222Y-309892D01*
X660622Y-309226D01*
X659822Y-308959D01*
G01X665922Y-310292D02*
X666522Y-309492D01*
X667222Y-309092D01*
X668022Y-308959D01*
X669022Y-309226D01*
X669722Y-309892D01*
X669922Y-310692D01*
X669822Y-311493D01*
X669422Y-312159D01*
X667422Y-313492D01*
X666522Y-314426D01*
X665922Y-315759D01*
X665722Y-316959D01*
X669922D01*
G01X673922Y-310292D02*
X674522Y-309492D01*
X675222Y-309092D01*
X676022Y-308959D01*
X677022Y-309226D01*
X677722Y-309892D01*
X677922Y-310692D01*
X677822Y-311493D01*
X677422Y-312159D01*
X675422Y-313492D01*
X674522Y-314426D01*
X673922Y-315759D01*
X673722Y-316959D01*
X677922D01*
G01X682022Y-317226D02*
X685622Y-308959D01*
G01X691822Y-316959D02*
Y-308959D01*
X690622Y-310559D01*
G01Y-316959D02*
X693022D01*
G01X697922Y-310292D02*
X698522Y-309492D01*
X699222Y-309092D01*
X700022Y-308959D01*
X701022Y-309226D01*
X701722Y-309892D01*
X701922Y-310692D01*
X701822Y-311493D01*
X701422Y-312159D01*
X699422Y-313492D01*
X698522Y-314426D01*
X697922Y-315759D01*
X697722Y-316959D01*
X701922D01*
G01X706022Y-317226D02*
X709622Y-308959D01*
G01X715822D02*
X715022Y-309226D01*
X714422Y-309892D01*
X714022Y-310692D01*
X713722Y-311759D01*
X713622Y-312959D01*
X713722Y-314159D01*
X714022Y-315226D01*
X714422Y-316026D01*
X715022Y-316692D01*
X715822Y-316959D01*
X716622Y-316692D01*
X717222Y-316026D01*
X717622Y-315226D01*
X717922Y-314159D01*
X718022Y-312959D01*
X717922Y-311759D01*
X717622Y-310692D01*
X717222Y-309892D01*
X716622Y-309226D01*
X715822Y-308959D01*
G01X722122Y-316026D02*
X722822Y-316692D01*
X723622Y-316959D01*
X724422Y-316692D01*
X725122Y-315893D01*
X725622Y-314692D01*
X725822Y-313492D01*
Y-312026D01*
X725622Y-310826D01*
X725122Y-309759D01*
X724522Y-309226D01*
X723822Y-308959D01*
X723022Y-309226D01*
X722422Y-309759D01*
X722022Y-310559D01*
X721822Y-311626D01*
X722022Y-312559D01*
X722522Y-313492D01*
X723122Y-314026D01*
X723822Y-314159D01*
X724622Y-313893D01*
X725222Y-313226D01*
X725822Y-312026D01*
G01X649622Y-291959D02*
Y-283959D01*
X651622D01*
X652422Y-284359D01*
X653022Y-284892D01*
X653522Y-285692D01*
X653922Y-286626D01*
X654022Y-287959D01*
X653922Y-289292D01*
X653522Y-290226D01*
X653022Y-291026D01*
X652422Y-291559D01*
X651622Y-291959D01*
X649622D01*
G01X657322D02*
X659822Y-283959D01*
X662322Y-291959D01*
G01X661422Y-289159D02*
X658222D01*
G01X667822Y-283959D02*
X667022Y-284226D01*
X666422Y-284892D01*
X666022Y-285692D01*
X665722Y-286759D01*
X665622Y-287959D01*
X665722Y-289159D01*
X666022Y-290226D01*
X666422Y-291026D01*
X667022Y-291692D01*
X667822Y-291959D01*
X668622Y-291692D01*
X669222Y-291026D01*
X669622Y-290226D01*
X669922Y-289159D01*
X670022Y-287959D01*
X669922Y-286759D01*
X669622Y-285692D01*
X669222Y-284892D01*
X668622Y-284226D01*
X667822Y-283959D01*
G01X673922Y-291959D02*
Y-283959D01*
X677722D01*
G01X676322Y-287826D02*
X673922D01*
G01X683822Y-283959D02*
X683022Y-284226D01*
X682422Y-284892D01*
X682022Y-285692D01*
X681722Y-286759D01*
X681622Y-287959D01*
X681722Y-289159D01*
X682022Y-290226D01*
X682422Y-291026D01*
X683022Y-291692D01*
X683822Y-291959D01*
X684622Y-291692D01*
X685222Y-291026D01*
X685622Y-290226D01*
X685922Y-289159D01*
X686022Y-287959D01*
X685922Y-286759D01*
X685622Y-285692D01*
X685222Y-284892D01*
X684622Y-284226D01*
X683822Y-283959D01*
G01X691822D02*
Y-291959D01*
G01X689522Y-283959D02*
X694122D01*
G01X697922Y-291959D02*
Y-283959D01*
X701722D01*
G01X700322Y-287826D02*
X697922D01*
G01X708622Y-287692D02*
X709022Y-287292D01*
X709322Y-286626D01*
X709522Y-285692D01*
X709322Y-284892D01*
X708922Y-284359D01*
X708222Y-283959D01*
X705522D01*
Y-291959D01*
X708822D01*
X709522Y-291426D01*
X709922Y-290626D01*
X710122Y-289692D01*
X709922Y-288759D01*
X709322Y-287959D01*
X708622Y-287692D01*
X705522D01*
G01X713922Y-288626D02*
X714622Y-287692D01*
X715222Y-287159D01*
X716022Y-286892D01*
X716722Y-287159D01*
X717222Y-287692D01*
X717622Y-288492D01*
X717722Y-289426D01*
X717622Y-290226D01*
X717222Y-291026D01*
X716622Y-291692D01*
X715922Y-291959D01*
X715122Y-291692D01*
X714422Y-290893D01*
X714022Y-289692D01*
X713922Y-288359D01*
X714122Y-286626D01*
X714422Y-285692D01*
X714922Y-284759D01*
X715622Y-284092D01*
X716322Y-283959D01*
X717022Y-284226D01*
X717522Y-284892D01*
G01X721622Y-291959D02*
Y-283959D01*
X723622D01*
X724422Y-284359D01*
X725022Y-284892D01*
X725522Y-285692D01*
X725922Y-286626D01*
X726022Y-287959D01*
X725922Y-289292D01*
X725522Y-290226D01*
X725022Y-291026D01*
X724422Y-291559D01*
X723622Y-291959D01*
X721622D01*
G01X731822Y-283959D02*
X731022Y-284226D01*
X730422Y-284892D01*
X730022Y-285692D01*
X729722Y-286759D01*
X729622Y-287959D01*
X729722Y-289159D01*
X730022Y-290226D01*
X730422Y-291026D01*
X731022Y-291692D01*
X731822Y-291959D01*
X732622Y-291692D01*
X733222Y-291026D01*
X733622Y-290226D01*
X733922Y-289159D01*
X734022Y-287959D01*
X733922Y-286759D01*
X733622Y-285692D01*
X733222Y-284892D01*
X732622Y-284226D01*
X731822Y-283959D01*
G01X649862Y-270000D02*
Y-263700D01*
X652838D01*
G01X651742Y-266745D02*
X649862D01*
G01X657650Y-263700D02*
X657023Y-263910D01*
X656553Y-264435D01*
X656240Y-265065D01*
X656005Y-265905D01*
X655927Y-266850D01*
X656005Y-267795D01*
X656240Y-268635D01*
X656553Y-269265D01*
X657023Y-269790D01*
X657650Y-270000D01*
X658277Y-269790D01*
X658747Y-269265D01*
X659060Y-268635D01*
X659295Y-267795D01*
X659373Y-266850D01*
X659295Y-265905D01*
X659060Y-265065D01*
X658747Y-264435D01*
X658277Y-263910D01*
X657650Y-263700D01*
G01X663950D02*
Y-270000D01*
G01X662148Y-263700D02*
X665752D01*
G01X667900Y-272100D02*
X672600D01*
G01X674983Y-270000D02*
Y-263700D01*
X676863D01*
X677490Y-264015D01*
X677960Y-264750D01*
X678117Y-265590D01*
X677960Y-266430D01*
X677568Y-267060D01*
X676863Y-267375D01*
X674983D01*
G01X684573Y-264225D02*
X684103Y-263910D01*
X683555Y-263700D01*
X682928D01*
X682223Y-264015D01*
X681675Y-264540D01*
X681283Y-265170D01*
X680970Y-266220D01*
X680892Y-267165D01*
X681048Y-268110D01*
X681283Y-268740D01*
X681753Y-269370D01*
X682302Y-269790D01*
X682850Y-270000D01*
X683398D01*
X683947Y-269790D01*
X684417Y-269475D01*
X684808Y-269055D01*
G01X689777Y-266640D02*
X690090Y-266325D01*
X690325Y-265800D01*
X690482Y-265065D01*
X690325Y-264435D01*
X690012Y-264015D01*
X689463Y-263700D01*
X687348D01*
Y-270000D01*
X689933D01*
X690482Y-269580D01*
X690795Y-268950D01*
X690952Y-268215D01*
X690795Y-267480D01*
X690325Y-266850D01*
X689777Y-266640D01*
X687348D01*
G01X693100Y-272100D02*
X697800D01*
G01X700262Y-270000D02*
Y-263700D01*
X703238D01*
G01X702142Y-266745D02*
X700262D01*
G01X706092Y-270000D02*
X708050Y-263700D01*
X710008Y-270000D01*
G01X709303Y-267795D02*
X706797D01*
G01X712548Y-270000D02*
Y-263700D01*
X716152Y-270000D01*
Y-263700D01*
G01X718300Y-272100D02*
X723000D01*
G01X727577Y-266640D02*
X727890Y-266325D01*
X728125Y-265800D01*
X728282Y-265065D01*
X728125Y-264435D01*
X727812Y-264015D01*
X727263Y-263700D01*
X725148D01*
Y-270000D01*
X727733D01*
X728282Y-269580D01*
X728595Y-268950D01*
X728752Y-268215D01*
X728595Y-267480D01*
X728125Y-266850D01*
X727577Y-266640D01*
X725148D01*
G01X733250Y-270000D02*
X732623Y-269895D01*
X732075Y-269475D01*
X731605Y-268845D01*
X731292Y-268110D01*
X731135Y-267270D01*
Y-266430D01*
X731292Y-265590D01*
X731605Y-264855D01*
X732075Y-264225D01*
X732623Y-263805D01*
X733250Y-263700D01*
X733877Y-263805D01*
X734425Y-264225D01*
X734895Y-264855D01*
X735208Y-265590D01*
X735365Y-266430D01*
Y-267270D01*
X735208Y-268110D01*
X734895Y-268845D01*
X734425Y-269475D01*
X733877Y-269895D01*
X733250Y-270000D01*
G01X737592D02*
X739550Y-263700D01*
X741508Y-270000D01*
G01X740803Y-267795D02*
X738297D01*
G01X744283Y-270000D02*
Y-263700D01*
X746242D01*
X746868Y-264015D01*
X747260Y-264435D01*
X747417Y-265275D01*
X747260Y-266115D01*
X746790Y-266640D01*
X746242Y-266955D01*
X744283D01*
G01X746242D02*
X747417Y-270000D01*
G01X750427D02*
Y-263700D01*
X751993D01*
X752620Y-264015D01*
X753090Y-264435D01*
X753482Y-265065D01*
X753795Y-265800D01*
X753873Y-266850D01*
X753795Y-267900D01*
X753482Y-268635D01*
X753090Y-269265D01*
X752620Y-269685D01*
X751993Y-270000D01*
X750427D01*
G01X756100Y-272100D02*
X760800D01*
G01X762713Y-270000D02*
Y-263700D01*
X764750Y-268950D01*
X766787Y-263700D01*
Y-270000D01*
G01X769483D02*
Y-263700D01*
X771363D01*
X771990Y-264015D01*
X772460Y-264750D01*
X772617Y-265590D01*
X772460Y-266430D01*
X772068Y-267060D01*
X771363Y-267375D01*
X769483D01*
G01X775627Y-269055D02*
X776097Y-269580D01*
X776645Y-269895D01*
X777350Y-270000D01*
X778055Y-269790D01*
X778603Y-269370D01*
X778995Y-268635D01*
X779073Y-267795D01*
X778917Y-266955D01*
X778525Y-266430D01*
X777977Y-266010D01*
X777428Y-265905D01*
X776880Y-266010D01*
X776175Y-266430D01*
X776410Y-263700D01*
X778525D01*
G01X783650D02*
X783023Y-263910D01*
X782553Y-264435D01*
X782240Y-265065D01*
X782005Y-265905D01*
X781927Y-266850D01*
X782005Y-267795D01*
X782240Y-268635D01*
X782553Y-269265D01*
X783023Y-269790D01*
X783650Y-270000D01*
X784277Y-269790D01*
X784747Y-269265D01*
X785060Y-268635D01*
X785295Y-267795D01*
X785373Y-266850D01*
X785295Y-265905D01*
X785060Y-265065D01*
X784747Y-264435D01*
X784277Y-263910D01*
X783650Y-263700D01*
G01X790890Y-270000D02*
Y-263700D01*
X787992Y-268215D01*
X791908D01*
G01X796250Y-270000D02*
X796798Y-269895D01*
X797425Y-269580D01*
X797817Y-269055D01*
X797973Y-268320D01*
X797817Y-267585D01*
X797347Y-266955D01*
X796642Y-266640D01*
X795858D01*
X795388Y-266430D01*
X794997Y-265905D01*
X794840Y-265170D01*
X795075Y-264435D01*
X795623Y-263910D01*
X796250Y-263700D01*
X796877Y-263910D01*
X797425Y-264435D01*
X797660Y-265170D01*
X797503Y-265905D01*
X797112Y-266430D01*
X796642Y-266640D01*
X795858D01*
X795153Y-266955D01*
X794683Y-267585D01*
X794527Y-268320D01*
X794683Y-269055D01*
X795075Y-269580D01*
X795702Y-269895D01*
X796250Y-270000D01*
G01X738322Y-319959D02*
Y-311959D01*
X737122Y-313559D01*
G01Y-319959D02*
X739522D01*
G01X744422Y-316626D02*
X745122Y-315692D01*
X745722Y-315159D01*
X746522Y-314892D01*
X747222Y-315159D01*
X747722Y-315692D01*
X748122Y-316492D01*
X748222Y-317426D01*
X748122Y-318226D01*
X747722Y-319026D01*
X747122Y-319692D01*
X746422Y-319959D01*
X745622Y-319692D01*
X744922Y-318893D01*
X744522Y-317692D01*
X744422Y-316359D01*
X744622Y-314626D01*
X744922Y-313692D01*
X745422Y-312759D01*
X746122Y-312092D01*
X746822Y-311959D01*
X747522Y-312226D01*
X748022Y-312892D01*
G01X754322Y-320226D02*
X754122Y-320092D01*
Y-319826D01*
X754322Y-319692D01*
X754522Y-319826D01*
Y-320092D01*
X754322Y-320226D01*
G01X760422Y-316626D02*
X761122Y-315692D01*
X761722Y-315159D01*
X762522Y-314892D01*
X763222Y-315159D01*
X763722Y-315692D01*
X764122Y-316492D01*
X764222Y-317426D01*
X764122Y-318226D01*
X763722Y-319026D01*
X763122Y-319692D01*
X762422Y-319959D01*
X761622Y-319692D01*
X760922Y-318893D01*
X760522Y-317692D01*
X760422Y-316359D01*
X760622Y-314626D01*
X760922Y-313692D01*
X761422Y-312759D01*
X762122Y-312092D01*
X762822Y-311959D01*
X763522Y-312226D01*
X764022Y-312892D01*
G01X783322Y-319959D02*
Y-311959D01*
X782122Y-313559D01*
G01Y-319959D02*
X784522D01*
G01X791122D02*
X791322Y-318226D01*
X791622Y-316759D01*
X792022Y-315426D01*
X792522Y-313959D01*
X793322Y-311959D01*
X789322D01*
G01X799322Y-320226D02*
X799122Y-320092D01*
Y-319826D01*
X799322Y-319692D01*
X799522Y-319826D01*
Y-320092D01*
X799322Y-320226D01*
G01X805422Y-313292D02*
X806022Y-312492D01*
X806722Y-312092D01*
X807522Y-311959D01*
X808522Y-312226D01*
X809222Y-312892D01*
X809422Y-313692D01*
X809322Y-314493D01*
X808922Y-315159D01*
X806922Y-316492D01*
X806022Y-317426D01*
X805422Y-318759D01*
X805222Y-319959D01*
X809422D01*
G01X803122Y-294959D02*
Y-286959D01*
X805122D01*
X805922Y-287359D01*
X806522Y-287892D01*
X807022Y-288692D01*
X807422Y-289626D01*
X807522Y-290959D01*
X807422Y-292292D01*
X807022Y-293226D01*
X806522Y-294026D01*
X805922Y-294559D01*
X805122Y-294959D01*
X803122D01*
G54D16*
G01X-63431Y1152816D02*
Y858517D01*
X-61604Y856690D01*
X-55243D01*
X-53431Y858502D01*
Y1152816D01*
G01X14925Y669000D02*
X17190Y666735D01*
Y640160D01*
X7600Y630570D01*
Y280632D01*
X14732Y273500D01*
X29000D01*
X31473Y275973D01*
X34527D01*
X42372Y268128D01*
X47676D01*
X54548Y275000D01*
X65546D01*
X66561Y273985D01*
G01X10500Y274500D02*
X5500Y279500D01*
Y631500D01*
X15090Y641090D01*
Y662835D01*
X14925Y663000D01*
G01X15713Y710009D02*
X15727D01*
Y693273D01*
X17000Y692000D01*
Y680501D01*
X5900Y669401D01*
Y647100D01*
X12000Y641000D01*
G01X12512Y647013D02*
X8000Y651525D01*
Y668499D01*
X19500Y679999D01*
Y694000D01*
X18353Y695147D01*
Y707865D01*
X18322Y707896D01*
Y709169D01*
X20327Y711174D01*
G01X15000Y1001300D02*
Y998800D01*
X12741Y996541D01*
Y983241D01*
X5449Y975949D01*
Y752670D01*
X8619Y749500D01*
Y726120D01*
X5500Y723001D01*
Y691350D01*
X12500Y684350D01*
Y679000D01*
G01X14925Y690000D02*
X13425D01*
X8000Y695425D01*
Y722531D01*
X10719Y725250D01*
Y750370D01*
X7549Y753540D01*
Y975019D01*
X17000Y984470D01*
Y990793D01*
X18561Y994561D01*
X27143Y1003143D01*
X34471D01*
X35784Y1001830D01*
X65434D01*
X69802Y1006198D01*
G01X26040Y245190D02*
Y245008D01*
X27048Y244000D01*
X30859D01*
X34500Y247641D01*
Y266419D01*
X32716Y268203D01*
Y273500D01*
G01X34000Y757000D02*
Y719438D01*
X39900Y713538D01*
Y693900D01*
X30139Y684139D01*
Y656639D01*
X24500Y651000D01*
Y644461D01*
X10500Y630461D01*
Y527680D01*
X14200Y523980D01*
Y501980D01*
X9700Y497480D01*
Y281830D01*
X15530Y276000D01*
X24000D01*
G01X11800Y284000D02*
X17635Y278165D01*
X35335D01*
X43028Y270472D01*
X45394D01*
X55650Y280728D01*
G01X37000Y756900D02*
Y719438D01*
X42000Y714438D01*
Y691500D01*
X36900Y686400D01*
Y658156D01*
X26871Y648127D01*
Y643820D01*
X13000Y629949D01*
Y528680D01*
X16500Y525180D01*
Y500880D01*
X11800Y496180D01*
Y284000D01*
G01X69000Y669745D02*
X68989D01*
X67834Y668590D01*
X62077D01*
X41500Y648013D01*
X37370D01*
X17800Y628443D01*
Y561200D01*
X40100Y538900D01*
Y511600D01*
X39690Y511190D01*
Y470290D01*
X43150Y466830D01*
Y427650D01*
X35618Y420118D01*
X34252D01*
G01X56925Y533500D02*
X56501D01*
X22939Y567062D01*
Y627543D01*
X37081Y641685D01*
X48015D01*
X55880Y633820D01*
X58197D01*
X59097Y634720D01*
Y649287D01*
X60934Y651124D01*
Y654210D01*
X65742Y659018D01*
X69048D01*
X71200Y661170D01*
Y677300D01*
X67900Y680600D01*
Y697896D01*
X43600Y722196D01*
Y835350D01*
X57920Y849670D01*
Y972377D01*
X84000Y998457D01*
Y1095499D01*
X64231Y1115268D01*
G01X84400Y64200D02*
X77973D01*
X74673Y67500D01*
X65687D01*
X52700Y80487D01*
Y112670D01*
X60555Y120525D01*
Y208080D01*
X77042Y247864D01*
Y334672D01*
X80204Y337834D01*
Y384866D01*
X47350Y417720D01*
Y468570D01*
X43890Y472030D01*
Y507680D01*
X44700Y508490D01*
Y541100D01*
X28900Y556900D01*
G01X34252Y56732D02*
X34732D01*
X50500Y72500D01*
Y113568D01*
X58361Y121429D01*
Y209229D01*
X74550Y248312D01*
Y335151D01*
X78000Y338601D01*
Y384100D01*
X45250Y416850D01*
Y467700D01*
X41790Y471160D01*
Y509950D01*
X42600Y510760D01*
Y539900D01*
X20300Y562200D01*
Y627900D01*
X36332Y643932D01*
X49632D01*
X52011Y646311D01*
Y653789D01*
X55704Y657482D01*
X57882D01*
X64400Y664000D01*
X68000D01*
G01X12389Y653509D02*
X10500Y655398D01*
Y667499D01*
X22000Y678999D01*
Y706500D01*
X20453Y708047D01*
G01X12419Y765261D02*
Y756673D01*
X20064Y749028D01*
Y714360D01*
X15713Y710009D01*
G01X14830Y763614D02*
Y757232D01*
X22164Y749898D01*
Y713011D01*
X20327Y711174D01*
G01X12819Y751500D02*
X9650Y754669D01*
Y974150D01*
X23702Y988202D01*
Y992261D01*
G01X30522Y1000288D02*
Y997169D01*
X33841Y993850D01*
Y978150D01*
X30472Y974781D01*
X27243D01*
X26990Y975034D01*
G01X40500Y1164000D02*
Y1161700D01*
X37500Y1158700D01*
X30316D01*
X26378Y1162638D01*
G01X68500Y70000D02*
X66157D01*
X54800Y81357D01*
Y111800D01*
X65000Y122000D01*
Y132155D01*
X62655Y134500D01*
Y206649D01*
X79372Y247069D01*
Y334031D01*
X82304Y336963D01*
Y386196D01*
X77900Y390600D01*
Y394700D01*
X69500Y403100D01*
Y414900D01*
X64120Y420280D01*
Y430220D01*
X62875Y431465D01*
Y448350D01*
X63000Y448475D01*
Y481925D01*
X56925Y488000D01*
G01X44500Y272767D02*
Y285500D01*
X46500Y287500D01*
Y299500D01*
X48334Y301334D01*
X53343D01*
G01X60475Y424728D02*
X50050Y435153D01*
Y469690D01*
X46590Y473150D01*
Y506402D01*
X51461Y511273D01*
X59773D01*
X66100Y517600D01*
Y520600D01*
X70650Y525150D01*
Y534750D01*
X92768Y556868D01*
Y564232D01*
X91400Y565600D01*
Y584669D01*
X100533Y607189D01*
X100066Y608293D01*
X97458Y609351D01*
X96991Y610455D01*
X97444Y611571D01*
X98548Y612039D01*
X101156Y610981D01*
X102261Y611449D01*
X104394Y616708D01*
X103927Y617813D01*
X101488Y618802D01*
X101021Y619907D01*
X101474Y621023D01*
X102578Y621490D01*
X105017Y620501D01*
X106121Y620968D01*
X108601Y627084D01*
G01X60475Y429228D02*
X52750Y436953D01*
Y459390D01*
X53280Y459920D01*
Y477160D01*
X51990Y478450D01*
Y501884D01*
X52513Y502407D01*
Y502513D01*
X55800Y505800D01*
X58044D01*
X58244Y506000D01*
X58500D01*
X69000Y516500D01*
Y519400D01*
X73500Y523900D01*
Y533500D01*
X95649Y555649D01*
Y565283D01*
X94100Y566832D01*
Y582943D01*
X117044Y639516D01*
X118079Y639954D01*
G01X49689Y474203D02*
X49290Y474602D01*
Y503838D01*
X53952Y508500D01*
X56925D01*
G01X58500Y441000D02*
X55450Y444050D01*
Y456110D01*
X56040Y456700D01*
Y479260D01*
X54700Y480600D01*
Y500775D01*
X56925Y503000D01*
G01X52800Y813500D02*
Y725525D01*
X72275Y706050D01*
X77350D01*
X79871Y703529D01*
Y653845D01*
X68408Y642382D01*
Y563236D01*
X64226Y553139D01*
Y536126D01*
X63290Y535190D01*
Y526470D01*
X58026Y521206D01*
X56382D01*
X54873Y519697D01*
Y515552D01*
X56925Y513500D01*
G01X68000Y676500D02*
X62000D01*
X49500Y689000D01*
Y710118D01*
X39400Y720218D01*
Y778356D01*
X34252Y783504D01*
G01Y1146890D02*
X45600Y1135542D01*
Y1133900D01*
X61686Y1117814D01*
Y1114814D01*
X80823Y1095677D01*
Y998250D01*
X55820Y973247D01*
Y850540D01*
X41500Y836220D01*
Y721088D01*
X51600Y710988D01*
Y696850D01*
X59475Y688975D01*
G01X75000Y1196500D02*
Y1194499D01*
X51400Y1170899D01*
Y1131312D01*
X86100Y1096612D01*
Y997557D01*
X60391Y971848D01*
Y848863D01*
X45713Y834185D01*
Y723083D01*
X70050Y698746D01*
Y681750D01*
X73300Y678500D01*
Y659296D01*
X61318Y647314D01*
Y563771D01*
X57000Y553347D01*
Y538500D01*
G01X47813Y833013D02*
Y724083D01*
X72400Y699496D01*
Y683000D01*
X75400Y680000D01*
Y658424D01*
X63430Y646454D01*
Y563005D01*
X59830Y554314D01*
Y538040D01*
X59090Y537300D01*
Y530665D01*
X56925Y528500D01*
G01X77518Y1138500D02*
X77168D01*
X75468Y1140200D01*
Y1157032D01*
X69500Y1163000D01*
X60500D01*
X53886Y1156386D01*
Y1131796D01*
X88200Y1097482D01*
Y996687D01*
X62491Y970978D01*
Y847601D01*
X50400Y835510D01*
Y724896D01*
X74900Y700396D01*
Y683500D01*
X77600Y680800D01*
Y654591D01*
X65918Y642909D01*
Y563218D01*
X62000Y553758D01*
Y537050D01*
X61190Y536240D01*
Y527765D01*
X56925Y523500D01*
G01X51852Y1012249D02*
Y1010216D01*
X48492Y1006856D01*
G01X53000Y1026000D02*
X55500Y1023500D01*
Y1015897D01*
X51852Y1012249D01*
G01X60475Y79692D02*
X57774Y82393D01*
Y105374D01*
X69000Y116600D01*
Y118500D01*
X79000Y128500D01*
Y133501D01*
X67518Y144983D01*
Y205846D01*
X85370Y249007D01*
Y333240D01*
X87504Y335374D01*
Y399423D01*
X91007Y402926D01*
Y425793D01*
X83254Y433546D01*
Y459253D01*
X91500Y467499D01*
Y475499D01*
X103500Y487499D01*
Y508839D01*
X105590Y510929D01*
Y518590D01*
X110000Y523000D01*
Y536000D01*
X114000Y540000D01*
Y558674D01*
X110200Y562474D01*
Y587346D01*
X128837Y633363D01*
X131500Y634500D01*
G01X135000Y637500D02*
Y635501D01*
X129000Y621028D01*
Y620932D01*
X128700Y620203D01*
Y582043D01*
X119005Y558629D01*
X119000Y558579D01*
Y549514D01*
X119006Y549463D01*
X119050Y549409D01*
X122189Y546270D01*
Y502399D01*
X111050Y491260D01*
Y482050D01*
X85954Y456954D01*
Y435045D01*
X93707Y427292D01*
Y401807D01*
X90204Y398304D01*
Y334254D01*
X88070Y332120D01*
Y248468D01*
X70218Y205309D01*
Y146102D01*
X82000Y134320D01*
Y127500D01*
X71999Y117499D01*
Y115500D01*
X68000Y111501D01*
Y100501D01*
X61000Y93501D01*
Y84192D01*
G01X79500Y86925D02*
Y98500D01*
X77000Y101000D01*
Y105000D01*
X82500Y110500D01*
Y122600D01*
X86000Y126100D01*
Y134139D01*
X72918Y147221D01*
Y204772D01*
X90770Y247929D01*
Y331000D01*
X92904Y333134D01*
Y396903D01*
X96407Y400406D01*
Y450408D01*
X127500Y481501D01*
Y487434D01*
X136300Y496234D01*
Y501909D01*
X133730Y504479D01*
Y552972D01*
X128500Y558202D01*
Y570000D01*
X131400Y572900D01*
Y619668D01*
X132825Y623127D01*
Y623203D01*
X137696Y634952D01*
X137700Y634961D01*
Y678950D01*
X129380Y687270D01*
Y693120D01*
X128000Y694500D01*
G01X71500Y130000D02*
X64818Y136682D01*
Y206383D01*
X82670Y249545D01*
Y334359D01*
X84804Y336493D01*
Y400542D01*
X88307Y404045D01*
Y417193D01*
X77090Y428410D01*
Y445857D01*
X75300Y447647D01*
Y461757D01*
X71057Y466000D01*
Y483868D01*
X56925Y498000D01*
G01X86000Y92000D02*
Y104000D01*
X91000Y109000D01*
Y135500D01*
X77251Y149249D01*
Y204252D01*
X94970Y247092D01*
Y329260D01*
X97104Y331394D01*
Y395027D01*
X100607Y398530D01*
Y442437D01*
X116670Y458500D01*
X127800D01*
X131500Y462200D01*
Y470000D01*
X146999Y485499D01*
Y490924D01*
X150575Y494500D01*
G01X79500Y104425D02*
Y104530D01*
X84600Y109630D01*
Y121730D01*
X88100Y125230D01*
Y135009D01*
X75151Y147958D01*
Y204673D01*
X92870Y247511D01*
Y330130D01*
X95004Y332264D01*
Y395897D01*
X98507Y399400D01*
Y448978D01*
X132500Y482971D01*
Y486501D01*
X139347Y493348D01*
Y502154D01*
X135830Y505671D01*
Y554217D01*
X131000Y559047D01*
Y569001D01*
X133500Y571501D01*
Y619251D01*
X134925Y622711D01*
Y622784D01*
X139800Y634542D01*
Y685777D01*
X133575Y692000D01*
G01X78500Y406000D02*
X75500Y409000D01*
Y426500D01*
X72922Y429078D01*
Y444824D01*
X65950Y451796D01*
Y466854D01*
X67910Y468814D01*
Y482015D01*
X56925Y493000D01*
G01X58500Y454500D02*
X58210Y454790D01*
Y481790D01*
X57000Y483000D01*
G01X79463Y429962D02*
Y446454D01*
X77400Y448517D01*
Y461201D01*
X82500Y466301D01*
Y474405D01*
X98650Y490555D01*
Y502899D01*
X95963Y505586D01*
Y515752D01*
X105125Y524914D01*
Y533850D01*
X102000Y536975D01*
Y555000D01*
X98424Y558576D01*
Y566321D01*
X102700Y570597D01*
Y588812D01*
X123563Y640330D01*
Y646552D01*
X118051Y652064D01*
Y689349D01*
X117500Y689900D01*
G01X69000Y771500D02*
X66500Y769000D01*
Y752622D01*
X68548Y750574D01*
Y726549D01*
X71016Y724081D01*
Y717484D01*
X76950Y711550D01*
X77350D01*
X82367Y706533D01*
Y652995D01*
X70650Y641278D01*
Y562239D01*
X66413Y552010D01*
Y535142D01*
X65390Y534119D01*
Y524756D01*
X59134Y518500D01*
X56925D01*
G01X78457Y634010D02*
Y633634D01*
X85350Y626741D01*
Y600169D01*
X79300Y585561D01*
Y555800D01*
X72500Y549000D01*
Y541500D01*
G01X75396Y544500D02*
Y547896D01*
X82000Y554500D01*
Y585024D01*
X88050Y599632D01*
Y627942D01*
X78677Y637315D01*
G01X78457Y634010D02*
X78149D01*
X76401Y635758D01*
Y638726D01*
X91532Y653857D01*
Y663261D01*
G01X88300Y639800D02*
Y641300D01*
X98223Y651223D01*
Y664761D01*
X93600Y669384D01*
Y709683D01*
X82778Y720505D01*
Y727722D01*
X74000Y736500D01*
Y752400D01*
X71700Y754700D01*
Y775300D01*
X73600Y777200D01*
Y798800D01*
X75000Y800200D01*
Y806500D01*
X82840Y814340D01*
Y825447D01*
X84319Y826926D01*
Y840123D01*
X80942Y843500D01*
Y865400D01*
X65191Y881151D01*
Y969859D01*
X90900Y995568D01*
Y1098601D01*
X56742Y1132759D01*
Y1155242D01*
X61500Y1160000D01*
G01X91532Y663261D02*
X88100Y666693D01*
Y707475D01*
X74075Y721500D01*
G01X95032Y660000D02*
Y664133D01*
X90900Y668265D01*
Y708500D01*
X74075Y725325D01*
Y726500D01*
G01X76725Y749500D02*
X81530Y754305D01*
Y782370D01*
X79100Y784800D01*
Y806100D01*
X83000Y810000D01*
G01X87500Y634700D02*
Y635805D01*
X101023Y649328D01*
Y665780D01*
X96300Y670503D01*
Y710802D01*
X85540Y721562D01*
Y749410D01*
X86330Y750200D01*
Y786370D01*
X85540Y787160D01*
Y814500D01*
X85800Y814760D01*
Y824588D01*
X87019Y825807D01*
Y840378D01*
X88200Y841559D01*
Y862415D01*
X67891Y882724D01*
Y968740D01*
X93600Y994449D01*
Y1100400D01*
X76230Y1117770D01*
Y1118930D01*
X78320Y1121020D01*
Y1122180D01*
X77500Y1123000D01*
X76340D01*
X74250Y1120910D01*
X73090D01*
X72270Y1121730D01*
Y1122890D01*
X74360Y1124980D01*
Y1126140D01*
X73540Y1126960D01*
X72380D01*
X70290Y1124870D01*
X69130D01*
X59598Y1134402D01*
Y1151123D01*
X60475Y1152000D01*
G01X94000Y818500D02*
X96295Y820795D01*
Y864900D01*
X75291Y885904D01*
Y966381D01*
X100500Y991590D01*
Y1121259D01*
X97407Y1124352D01*
Y1157988D01*
X86000Y1169395D01*
Y1176575D01*
G01X101500Y824271D02*
Y863655D01*
X77391Y887764D01*
Y965511D01*
X102600Y990720D01*
Y1110412D01*
X112750Y1120562D01*
Y1139908D01*
X120261Y1147419D01*
Y1162762D01*
X128490Y1170991D01*
Y1183817D01*
X126360Y1185947D01*
G01X101284Y671500D02*
X99000Y673784D01*
Y712129D01*
X88500Y722629D01*
Y747361D01*
X89030Y747891D01*
Y788770D01*
X88500Y789300D01*
Y823469D01*
X89719Y824688D01*
Y839259D01*
X90900Y840440D01*
Y863534D01*
X71000Y883434D01*
Y968030D01*
X96300Y993330D01*
Y1114699D01*
X89000Y1121999D01*
Y1151501D01*
X83076Y1157425D01*
X79000D01*
G01Y1173425D02*
X95307Y1157118D01*
Y1123482D01*
X98400Y1120389D01*
Y992460D01*
X73191Y967251D01*
Y884818D01*
X93000Y865009D01*
Y838361D01*
X91819Y837180D01*
Y823818D01*
X90609Y822608D01*
Y791492D01*
X91130Y790971D01*
Y747021D01*
X90609Y746500D01*
Y724122D01*
X101298Y713433D01*
Y675511D01*
X101309Y675500D01*
G01X99000Y61000D02*
Y66001D01*
X100499Y67500D01*
X111377D01*
X118814Y74937D01*
Y76633D01*
X124224Y82043D01*
Y86800D01*
X115100Y95924D01*
Y115129D01*
X125000Y125029D01*
Y132001D01*
X125871Y132872D01*
Y201115D01*
X103970Y254008D01*
Y325371D01*
X106104Y327505D01*
Y381003D01*
X124000Y398899D01*
Y405499D01*
X119700Y409799D01*
Y411619D01*
X117600Y413719D01*
Y437832D01*
X126069Y446301D01*
X133106D01*
X149202Y462397D01*
Y473769D01*
X151635Y476202D01*
G01X154000Y471000D02*
X153500Y470500D01*
Y462876D01*
X134225Y443601D01*
X127239D01*
X120300Y436662D01*
Y416840D01*
X127100Y410040D01*
Y398080D01*
X108804Y379784D01*
Y326104D01*
X106670Y323970D01*
Y254547D01*
X128571Y201653D01*
Y132428D01*
X130000Y130999D01*
Y126210D01*
X117800Y114010D01*
Y97043D01*
X126924Y87919D01*
Y80924D01*
X121614Y75614D01*
Y73853D01*
X105261Y57500D01*
X99883D01*
G01X118475Y83500D02*
X118476Y85322D01*
X108500Y95302D01*
Y124001D01*
X81545Y150956D01*
Y203639D01*
X99170Y246256D01*
Y327520D01*
X101304Y329654D01*
Y393190D01*
X104807Y396693D01*
Y439553D01*
X106850Y441596D01*
G01X112000Y88700D02*
X106400Y94300D01*
Y123099D01*
X79445Y150054D01*
Y204059D01*
X97070Y246674D01*
Y328390D01*
X99204Y330524D01*
Y394088D01*
X102707Y397591D01*
Y441567D01*
X117340Y456200D01*
X132290D01*
X137500Y461410D01*
Y472500D01*
X148000Y483000D01*
G01X150500Y489500D02*
Y482500D01*
X139800Y471800D01*
Y459835D01*
X131066Y451101D01*
X123201D01*
X112252Y440152D01*
Y438052D01*
X110137Y435937D01*
Y414181D01*
X114708Y409610D01*
Y401540D01*
X103404Y390236D01*
Y328784D01*
X101270Y326650D01*
Y253469D01*
X122300Y202681D01*
Y126148D01*
X112400Y116248D01*
Y94805D01*
X121524Y85681D01*
Y83523D01*
X115918Y77917D01*
Y75650D01*
G01X100835Y446500D02*
Y448336D01*
X125499Y473000D01*
X128500D01*
X141500Y486000D01*
Y516500D01*
G01X79500Y449925D02*
Y450025D01*
X80554Y451079D01*
Y460554D01*
X88500Y468500D01*
Y476499D01*
X100750Y488749D01*
Y510329D01*
X102890Y512469D01*
Y519709D01*
X107225Y524044D01*
Y534720D01*
X104800Y537145D01*
Y588398D01*
X125663Y639916D01*
Y647422D01*
X120782Y652303D01*
Y693218D01*
X118000Y696000D01*
G01X91593Y439000D02*
Y443182D01*
X93707Y445296D01*
Y451527D01*
X122000Y479820D01*
Y486001D01*
X130901Y494902D01*
Y547905D01*
X125000Y553806D01*
Y562500D01*
G01X91500Y434000D02*
X88654Y436846D01*
Y453494D01*
X110500Y475340D01*
Y477499D01*
X116500Y483499D01*
Y488580D01*
X125151Y497231D01*
Y548004D01*
X122000Y551155D01*
Y557000D01*
X121500Y557500D01*
G01X102075Y534000D02*
Y530550D01*
X93750Y522225D01*
Y500145D01*
X95184Y498711D01*
Y493787D01*
G01X85000Y562148D02*
Y585211D01*
X90750Y599093D01*
Y634751D01*
X90800Y634801D01*
Y635119D01*
X103998Y648317D01*
Y674370D01*
X104010Y674382D01*
Y676618D01*
X103998Y676630D01*
Y714912D01*
X96000Y722910D01*
Y767763D01*
X93830Y769933D01*
Y791468D01*
X107597Y805235D01*
Y832097D01*
X118208Y842708D01*
X121208D01*
X123500Y845000D01*
Y948409D01*
X113180Y973320D01*
X109500Y977000D01*
Y1106254D01*
X145500Y1142254D01*
Y1158500D01*
X142500Y1161500D01*
G01X97000Y569153D02*
Y581440D01*
X100000Y588838D01*
Y589338D01*
X120863Y640856D01*
Y644933D01*
X115150Y650646D01*
Y719519D01*
X107000Y727669D01*
Y772594D01*
X105000Y774594D01*
Y794500D01*
X120500Y810000D01*
Y819301D01*
X124000Y822801D01*
X136133D01*
X142404Y816530D01*
Y806025D01*
X141088Y804709D01*
G01X90680Y561766D02*
X89860D01*
X88700Y562926D01*
Y585891D01*
X93500Y597480D01*
Y634000D01*
X106798Y647298D01*
Y716291D01*
X98700Y724389D01*
Y768882D01*
X96530Y771052D01*
Y790349D01*
X111162Y804981D01*
Y831661D01*
X119412Y839911D01*
X122410D01*
X126287Y843788D01*
Y949042D01*
X115686Y974634D01*
X112200Y978120D01*
Y1104973D01*
X148681Y1141454D01*
Y1169819D01*
X142500Y1176000D01*
G01X99279Y781942D02*
Y772362D01*
X101400Y770241D01*
Y725508D01*
X109598Y717310D01*
Y645598D01*
X99051Y635051D01*
G01X78677Y637315D02*
X79145D01*
X95032Y653202D01*
Y660000D01*
G01X83000Y804000D02*
X81600Y802600D01*
Y786500D01*
X83630Y784470D01*
Y751319D01*
X82840Y750529D01*
Y742840D01*
X79975Y739975D01*
G01X99500Y787000D02*
X102133Y784367D01*
Y773457D01*
X104100Y771490D01*
Y726627D01*
X112388Y718339D01*
Y644496D01*
X106000Y638108D01*
Y634500D01*
G01X104500Y834500D02*
Y864400D01*
X79812Y889088D01*
Y964023D01*
X104700Y988911D01*
Y1109513D01*
X114850Y1119663D01*
Y1139038D01*
X122361Y1146549D01*
Y1161361D01*
X127000Y1166000D01*
G01X120500Y845000D02*
Y858500D01*
X116500Y862500D01*
X109370D01*
X81912Y889958D01*
Y963153D01*
X106800Y988041D01*
Y1108557D01*
X117000Y1118757D01*
Y1137788D01*
X124500Y1145288D01*
Y1148575D01*
G01X150575Y504500D02*
X156505Y498570D01*
Y462062D01*
X135344Y440901D01*
X128358D01*
X123000Y435543D01*
Y417959D01*
X129800Y411159D01*
Y396961D01*
X112500Y379661D01*
Y325600D01*
X109450Y322550D01*
Y255145D01*
X131271Y202442D01*
Y133547D01*
X132700Y132118D01*
Y120200D01*
X128000Y115500D01*
X123500D01*
G01X132350Y94273D02*
Y92971D01*
X133897Y91424D01*
X143924D01*
X150000Y97500D01*
Y135230D01*
X142450Y142780D01*
Y202122D01*
X121410Y252925D01*
Y319556D01*
X122700Y320846D01*
Y375000D01*
X140700Y393000D01*
X145000D01*
X154726Y402726D01*
X180426D01*
X187494Y409794D01*
Y480506D01*
X181920Y486080D01*
Y528660D01*
X183200Y529940D01*
Y547782D01*
X195894Y560476D01*
Y687137D01*
X186531Y696500D01*
X181000D01*
G01X127000Y77500D02*
X127425D01*
X129624Y79699D01*
Y94623D01*
X131676Y96675D01*
X143176D01*
X147900Y101399D01*
Y133644D01*
X139900Y141644D01*
Y202788D01*
X119310Y252507D01*
Y320428D01*
X120600Y321718D01*
Y376304D01*
X139397Y395101D01*
X144131D01*
X153856Y404826D01*
X179556D01*
X185394Y410664D01*
Y479606D01*
X179820Y485180D01*
Y529530D01*
X181100Y530810D01*
Y548660D01*
X193794Y561354D01*
Y686205D01*
X185999Y694000D01*
X179000D01*
G01X135500Y562500D02*
X147341Y550659D01*
Y519000D01*
X149631Y516710D01*
X155160D01*
X161905Y509965D01*
Y459824D01*
X137582Y435501D01*
X130596D01*
X128450Y433355D01*
Y422549D01*
X137500Y413499D01*
Y397023D01*
X117900Y377423D01*
Y322837D01*
X116600Y321537D01*
Y251993D01*
X137200Y202248D01*
Y140525D01*
X145000Y132725D01*
Y105317D01*
X143025Y103342D01*
X142500D01*
G01X133491Y560490D02*
X144500Y549481D01*
Y518022D01*
X150042Y512480D01*
X152491D01*
X159205Y505766D01*
Y460943D01*
X136463Y438201D01*
X129477D01*
X125750Y434474D01*
Y421430D01*
X132500Y414680D01*
Y395842D01*
X115200Y378542D01*
Y323956D01*
X113900Y322656D01*
Y251456D01*
X134500Y201709D01*
Y139001D01*
X138000Y135501D01*
Y113891D01*
X137449Y113340D01*
G01X169291Y96102D02*
X152500Y112893D01*
Y135700D01*
X144550Y143650D01*
Y202543D01*
X123510Y253343D01*
Y318110D01*
X124800Y319400D01*
Y374100D01*
X141200Y390500D01*
X145501D01*
X155248Y400247D01*
X181183D01*
X181244Y400254D01*
X181294Y400294D01*
X189594Y408594D01*
Y481406D01*
X184020Y486980D01*
Y527790D01*
X185300Y529070D01*
Y541541D01*
X191259Y547500D01*
G01X150575Y499500D02*
X153000Y497075D01*
Y481500D01*
X142300Y470800D01*
Y459365D01*
X131936Y449001D01*
X124950D01*
X114900Y438951D01*
Y412600D01*
X117000Y410500D01*
Y405000D01*
X118500Y403500D01*
G01X109000Y485000D02*
X108000Y486000D01*
Y498100D01*
X106950Y499150D01*
Y507950D01*
X108500Y509500D01*
Y512000D01*
G01X138428Y806903D02*
X138729Y807204D01*
Y815106D01*
X136321Y817514D01*
X132514D01*
X110036Y795036D01*
Y728744D01*
X121900Y716880D01*
Y696100D01*
X123840Y694160D01*
Y686830D01*
X127243Y683427D01*
Y678239D01*
X128063Y677419D01*
X130180D01*
X131000Y676599D01*
Y675439D01*
X130180Y674619D01*
X128063D01*
X127243Y673799D01*
Y672639D01*
X128063Y671819D01*
X130180D01*
X131000Y670999D01*
Y669839D01*
X130180Y669019D01*
X129389D01*
X128569Y668199D01*
Y639897D01*
X107500Y587872D01*
Y562442D01*
X106977Y561919D01*
G01X118711Y797500D02*
X112848Y791637D01*
Y765146D01*
X130297Y747697D01*
Y727936D01*
X144000Y714233D01*
Y644540D01*
X142770Y643310D01*
X141900D01*
Y634123D01*
X137644Y623858D01*
X137025Y622365D01*
Y564838D01*
X150500Y551363D01*
Y544500D01*
G01X121536Y749253D02*
X125500Y745289D01*
Y728131D01*
X128065Y725566D01*
G01X150300Y645900D02*
Y717519D01*
X141431Y726388D01*
Y746069D01*
X117165Y770335D01*
Y787695D01*
X127570Y798100D01*
X142896D01*
X145189Y800393D01*
Y824000D01*
X128987Y840202D01*
Y949681D01*
X118048Y976092D01*
X117668Y976472D01*
X114900Y979239D01*
Y1103400D01*
X134500Y1123000D01*
X137500D01*
X151381Y1136881D01*
Y1169881D01*
X167760Y1186260D01*
X169291D01*
G01X121841Y775967D02*
Y772754D01*
X154500Y740095D01*
Y657336D01*
X182900Y628936D01*
Y566549D01*
X159774Y543423D01*
Y533699D01*
X150575Y524500D01*
G01X119836Y761664D02*
X132492Y749008D01*
Y728711D01*
X146100Y715103D01*
Y643670D01*
X144000Y641570D01*
Y633704D01*
X139251Y622249D01*
X139125Y621946D01*
Y565708D01*
X153166Y551667D01*
Y542091D01*
X150575Y539500D01*
G01Y529500D02*
X157674Y536599D01*
Y544293D01*
X180800Y567419D01*
Y627492D01*
X152400Y655892D01*
Y738291D01*
X119578Y771113D01*
Y787125D01*
X128453Y796000D01*
X143766D01*
X147489Y799723D01*
Y824812D01*
X131087Y841214D01*
Y951109D01*
X119872Y978186D01*
X117000Y981058D01*
Y1102150D01*
X132175Y1117325D01*
G01X179000Y676500D02*
X182600Y672900D01*
Y651600D01*
X177647Y646647D01*
X171646D01*
X161467Y656826D01*
Y688967D01*
X162000Y689500D01*
Y739020D01*
X122567Y778453D01*
Y784488D01*
X124579Y786500D01*
X128500D01*
G01X150575Y534500D02*
X155266Y539191D01*
Y552537D01*
X141225Y566578D01*
Y621526D01*
X143214Y626323D01*
X145425Y631656D01*
X146100Y633285D01*
Y640700D01*
X148200Y642800D01*
Y716186D01*
X139292Y725094D01*
Y745238D01*
X114948Y769582D01*
Y788863D01*
X133246Y807161D01*
Y811300D01*
G01X147393Y995649D02*
Y994622D01*
X145228Y992457D01*
X123849D01*
X121936Y990544D01*
Y982537D01*
X123393Y981080D01*
X135458Y951950D01*
Y857808D01*
X161530Y831736D01*
Y774000D01*
X187041Y748489D01*
Y730000D01*
G01X119500Y992000D02*
Y981528D01*
X121653Y979375D01*
X133187Y951529D01*
Y857109D01*
X159349Y830947D01*
Y773211D01*
X184425Y748135D01*
Y738000D01*
G01X137449Y113340D02*
X139186Y111603D01*
Y101656D01*
X142000Y98842D01*
G01X150500Y247000D02*
X147000D01*
X140700Y253300D01*
Y261900D01*
X142400Y263600D01*
Y269800D01*
G01X187925Y701000D02*
Y698076D01*
X197994Y688007D01*
Y269294D01*
X189800Y261100D01*
X168988D01*
X159754Y270334D01*
X151999D01*
X147393Y265728D01*
G01X191991Y536336D02*
X195830Y532497D01*
Y509574D01*
X191991Y505735D01*
Y487949D01*
X195894Y484046D01*
Y284454D01*
X195800Y284360D01*
Y270200D01*
X189600Y264000D01*
X172300D01*
X163829Y272471D01*
X136482D01*
G01X132850Y421837D02*
X134513Y423500D01*
X145000D01*
X161500Y407000D01*
X178500D01*
X183294Y411794D01*
Y478206D01*
X174713Y486787D01*
Y545773D01*
X191694Y562754D01*
Y685335D01*
X186479Y690550D01*
X180900D01*
X180000Y689650D01*
Y685000D01*
X180500Y684500D01*
G01X130500Y432500D02*
X138400D01*
X164605Y458705D01*
Y541930D01*
X187100Y564425D01*
Y635500D01*
X185000Y637600D01*
Y646500D01*
X189500Y651000D01*
Y681500D01*
X183000Y688000D01*
X182500D01*
G01X129000Y468000D02*
Y470470D01*
X143960Y485430D01*
Y491639D01*
X147610Y495289D01*
Y506535D01*
X150575Y509500D01*
G01X141900Y645410D02*
Y713363D01*
X129697Y725566D01*
X128065D01*
G01X136500Y742000D02*
Y728500D01*
G01X150575Y519500D02*
X151871D01*
X161874Y529503D01*
Y542553D01*
X185000Y565679D01*
Y630323D01*
X156829Y658494D01*
Y687429D01*
X159500Y690100D01*
Y738500D01*
X125719Y772281D01*
X125654D01*
G01X132370Y788872D02*
Y786090D01*
X130437Y784157D01*
X126044D01*
X125144Y783257D01*
Y779166D01*
X164500Y739810D01*
Y688499D01*
X164028Y688027D01*
Y657972D01*
X173000Y649000D01*
X177000D01*
X180500Y652500D01*
Y670999D01*
X175475Y676024D01*
Y677475D01*
X177500Y679500D01*
G01X145600Y838100D02*
X145858D01*
X155126Y828832D01*
Y771374D01*
X175500Y751000D01*
Y705500D01*
X170900Y700900D01*
Y673075D01*
X175475Y668500D01*
G01X175858Y1000757D02*
X174035Y998934D01*
Y958163D01*
X139722Y923850D01*
Y860778D01*
X146000Y854500D01*
G01X149000D02*
X141822Y861678D01*
Y922791D01*
X176288Y957257D01*
Y996789D01*
X178389Y998890D01*
Y1004703D01*
X171622Y1011470D01*
Y1015816D01*
X169571Y1017867D01*
X158812D01*
X156899Y1015954D01*
Y1011669D01*
X154965Y1009735D01*
Y1007851D01*
X148839Y1001725D01*
X137149D01*
X136482Y1002392D01*
G01X164947Y1007500D02*
Y1008477D01*
X166853Y1010383D01*
X169215D01*
X170228Y1009370D01*
Y996272D01*
X171900Y994600D01*
Y958998D01*
X137622Y924720D01*
Y858762D01*
X163630Y832754D01*
Y775152D01*
X190300Y748482D01*
Y725200D01*
G01X161884Y1026048D02*
X156122D01*
X154500Y1024426D01*
Y1012712D01*
X152633Y1010845D01*
Y1009703D01*
X147229Y1004299D01*
G01X164947Y280728D02*
X163800Y279581D01*
Y275700D01*
X173400Y266100D01*
X188730D01*
X193700Y271070D01*
Y285230D01*
X193794Y285324D01*
Y483176D01*
X189800Y487170D01*
Y506560D01*
X193691Y510451D01*
Y531076D01*
X189800Y534967D01*
Y539000D01*
X192000Y541200D01*
Y544500D01*
X194000Y546500D01*
Y550000D01*
G01X162783Y301463D02*
X162246Y302000D01*
X159000D01*
X154800Y297800D01*
Y279386D01*
X158498Y275688D01*
X160777D01*
G01X169291Y459488D02*
X173279Y455500D01*
X179000D01*
X181000Y457500D01*
Y477000D01*
X172410Y485590D01*
Y546765D01*
X189594Y563949D01*
Y636406D01*
X187500Y638500D01*
Y643500D01*
G01X148281Y838882D02*
X157226Y829937D01*
Y772244D01*
X177600Y751870D01*
Y704600D01*
X173000Y700000D01*
Y675000D01*
X175500Y672500D01*
G01X169291Y822874D02*
X173265Y818900D01*
X179200D01*
X185900Y812200D01*
Y773593D01*
X180400Y768093D01*
Y762100D01*
X195000Y747500D01*
Y719000D01*
X175500Y699500D01*
Y685000D01*
X178500Y682000D01*
X180530D01*
X185000Y677530D01*
Y651000D01*
X182500Y648500D01*
Y641600D01*
G01X149658Y974968D02*
X152969D01*
X155829Y977828D01*
Y989315D01*
X158500Y991986D01*
Y996638D01*
X164337Y1002475D01*
G01X164000Y1171500D02*
X166900Y1174400D01*
X173277D01*
X177165Y1170512D01*
G01X189250Y541750D02*
X187400Y539900D01*
Y528200D01*
X186120Y526920D01*
Y487880D01*
X191694Y482306D01*
Y286194D01*
X183900Y278400D01*
X180273D01*
X175858Y273985D01*
M02*
